FILE_TYPE = MACRO_DRAWING;
SET COLOR_WIRE YELLOW;
SET COLOR_PROP MONO;
SET COLOR_DOT WHITE;
SET COLOR_ARC YELLOW;
SET COLOR_BODY GREEN;
SET COLOR_NOTE MONO;
SET PROP_DISPLAY VALUE;
SET PAGE_NUMBER P28;
FORCEADD OFFPAGE..5
(-6425 525);
FORCEPROP 2 LAST $XR1 54 
J 0
(-6769 525);
DISPLAY 0.638298 (-6769 525);
PAINT MONO (-6769 525);
FORCEPROP 2 LAST $XR0 53 
J 0
(-6679 525);
DISPLAY 0.638298 (-6679 525);
PAINT MONO (-6679 525);
FORCEPROP 2 LAST PATH I1
J 0
(-6375 600);
DISPLAY 1.021277 (-6375 600);
PAINT ORANGE (-6375 600);
DISPLAY INVISIBLE (-6375 600);
FORCEPROP 1 LAST COMMENT_BODY TRUE
J 0
(-6325 450);
DISPLAY 1.170213 (-6325 450);
PAINT GREEN (-6325 450);
DISPLAY INVISIBLE (-6325 450);
FORCEPROP 1 LAST OFFPAGE TRUE
J 0
(-6100 400);
DISPLAY 1.170213 (-6100 400);
PAINT GREEN (-6100 400);
DISPLAY INVISIBLE (-6100 400);
FORCEPROP 2 LAST CDS_LIB mstr_standard
J 0
(-6425 525);
PAINT MONO (-6425 525);
DISPLAY INVISIBLE (-6425 525);
FORCEADD TAP..6
(-5575 875);
FORCEPROP 3 LASTPIN (-5525 875) SIG_NAME M_F_CLK_DP<1>
J 0
(-5515 885);
DISPLAY 0.659574 (-5515 885);
PAINT MONO (-5515 885);
DISPLAY INVISIBLE (-5515 885);
FORCEPROP 1 LASTPIN (-5525 875) BN 1
J 0
(-5577 883);
DISPLAY 0.617021 (-5577 883);
PAINT PINK (-5577 883);
FORCEPROP 1 LAST PATH I10
J 0
(-5577 875);
DISPLAY 0.872340 (-5577 875);
PAINT GREEN (-5577 875);
DISPLAY INVISIBLE (-5577 875);
FORCEPROP 1 LAST HDL_TAP TRUE
J 0
(-5250 750);
DISPLAY 1.595745 (-5250 750);
PAINT GREEN (-5250 750);
DISPLAY INVISIBLE (-5250 750);
FORCEPROP 1 LAST BODY_TYPE PLUMBING
J 0
(-5575 825);
DISPLAY 1.595745 (-5575 825);
PAINT GREEN (-5575 825);
DISPLAY INVISIBLE (-5575 825);
FORCEPROP 2 LAST CDS_LIB mstr_standard
J 0
(-5575 875);
PAINT MONO (-5575 875);
DISPLAY INVISIBLE (-5575 875);
FORCEADD TAP..6
R 2
(-2850 1425);
FORCEPROP 3 LASTPIN (-2900 1425) SIG_NAME M_F_ODT<0>
J 0
(-2890 1435);
DISPLAY 0.659574 (-2890 1435);
PAINT MONO (-2890 1435);
DISPLAY INVISIBLE (-2890 1435);
FORCEPROP 1 LASTPIN (-2900 1425) BN 0
J 2
(-2848 1433);
DISPLAY 0.617021 (-2848 1433);
PAINT PINK (-2848 1433);
FORCEPROP 1 LAST PATH I100
J 2
(-2848 1425);
DISPLAY 0.872340 (-2848 1425);
PAINT GREEN (-2848 1425);
DISPLAY INVISIBLE (-2848 1425);
FORCEPROP 1 LAST HDL_TAP TRUE
J 2
(-3175 1300);
DISPLAY 1.595745 (-3175 1300);
PAINT GREEN (-3175 1300);
DISPLAY INVISIBLE (-3175 1300);
FORCEPROP 1 LAST BODY_TYPE PLUMBING
J 2
(-2850 1375);
DISPLAY 1.595745 (-2850 1375);
PAINT GREEN (-2850 1375);
DISPLAY INVISIBLE (-2850 1375);
FORCEPROP 2 LAST CDS_LIB mstr_standard
J 0
(-2850 1425);
PAINT MONO (-2850 1425);
DISPLAY INVISIBLE (-2850 1425);
FORCEADD TAP..6
R 2
(-2850 1575);
FORCEPROP 3 LASTPIN (-2900 1575) SIG_NAME M_F_ODT<3>
J 0
(-2890 1585);
DISPLAY 0.659574 (-2890 1585);
PAINT MONO (-2890 1585);
DISPLAY INVISIBLE (-2890 1585);
FORCEPROP 1 LASTPIN (-2900 1575) BN 3
J 2
(-2848 1583);
DISPLAY 0.617021 (-2848 1583);
PAINT PINK (-2848 1583);
FORCEPROP 1 LAST PATH I101
J 2
(-2848 1575);
DISPLAY 0.872340 (-2848 1575);
PAINT GREEN (-2848 1575);
DISPLAY INVISIBLE (-2848 1575);
FORCEPROP 1 LAST HDL_TAP TRUE
J 2
(-3175 1450);
DISPLAY 1.595745 (-3175 1450);
PAINT GREEN (-3175 1450);
DISPLAY INVISIBLE (-3175 1450);
FORCEPROP 1 LAST BODY_TYPE PLUMBING
J 2
(-2850 1525);
DISPLAY 1.595745 (-2850 1525);
PAINT GREEN (-2850 1525);
DISPLAY INVISIBLE (-2850 1525);
FORCEPROP 2 LAST CDS_LIB mstr_standard
J 0
(-2850 1575);
PAINT MONO (-2850 1575);
DISPLAY INVISIBLE (-2850 1575);
FORCEADD TAP..6
R 2
(-2850 1525);
FORCEPROP 3 LASTPIN (-2900 1525) SIG_NAME M_F_ODT<2>
J 0
(-2890 1535);
DISPLAY 0.659574 (-2890 1535);
PAINT MONO (-2890 1535);
DISPLAY INVISIBLE (-2890 1535);
FORCEPROP 1 LASTPIN (-2900 1525) BN 2
J 2
(-2848 1533);
DISPLAY 0.617021 (-2848 1533);
PAINT PINK (-2848 1533);
FORCEPROP 1 LAST PATH I102
J 2
(-2848 1525);
DISPLAY 0.872340 (-2848 1525);
PAINT GREEN (-2848 1525);
DISPLAY INVISIBLE (-2848 1525);
FORCEPROP 1 LAST HDL_TAP TRUE
J 2
(-3175 1400);
DISPLAY 1.595745 (-3175 1400);
PAINT GREEN (-3175 1400);
DISPLAY INVISIBLE (-3175 1400);
FORCEPROP 1 LAST BODY_TYPE PLUMBING
J 2
(-2850 1475);
DISPLAY 1.595745 (-2850 1475);
PAINT GREEN (-2850 1475);
DISPLAY INVISIBLE (-2850 1475);
FORCEPROP 2 LAST CDS_LIB mstr_standard
J 0
(-2850 1525);
PAINT MONO (-2850 1525);
DISPLAY INVISIBLE (-2850 1525);
FORCEADD TAP..6
R 2
(-2850 1675);
FORCEPROP 3 LASTPIN (-2900 1675) SIG_NAME M_F_CKE<0>
J 0
(-2890 1685);
DISPLAY 0.659574 (-2890 1685);
PAINT MONO (-2890 1685);
DISPLAY INVISIBLE (-2890 1685);
FORCEPROP 1 LASTPIN (-2900 1675) BN 0
J 2
(-2848 1683);
DISPLAY 0.617021 (-2848 1683);
PAINT PINK (-2848 1683);
FORCEPROP 1 LAST PATH I103
J 2
(-2848 1675);
DISPLAY 0.872340 (-2848 1675);
PAINT GREEN (-2848 1675);
DISPLAY INVISIBLE (-2848 1675);
FORCEPROP 1 LAST HDL_TAP TRUE
J 2
(-3175 1550);
DISPLAY 1.595745 (-3175 1550);
PAINT GREEN (-3175 1550);
DISPLAY INVISIBLE (-3175 1550);
FORCEPROP 1 LAST BODY_TYPE PLUMBING
J 2
(-2850 1625);
DISPLAY 1.595745 (-2850 1625);
PAINT GREEN (-2850 1625);
DISPLAY INVISIBLE (-2850 1625);
FORCEPROP 2 LAST CDS_LIB mstr_standard
J 0
(-2850 1675);
PAINT MONO (-2850 1675);
DISPLAY INVISIBLE (-2850 1675);
FORCEADD TAP..6
R 2
(-2850 1725);
FORCEPROP 3 LASTPIN (-2900 1725) SIG_NAME M_F_CKE<1>
J 0
(-2890 1735);
DISPLAY 0.659574 (-2890 1735);
PAINT MONO (-2890 1735);
DISPLAY INVISIBLE (-2890 1735);
FORCEPROP 1 LASTPIN (-2900 1725) BN 1
J 2
(-2848 1733);
DISPLAY 0.617021 (-2848 1733);
PAINT PINK (-2848 1733);
FORCEPROP 1 LAST PATH I104
J 2
(-2848 1725);
DISPLAY 0.872340 (-2848 1725);
PAINT GREEN (-2848 1725);
DISPLAY INVISIBLE (-2848 1725);
FORCEPROP 1 LAST HDL_TAP TRUE
J 2
(-3175 1600);
DISPLAY 1.595745 (-3175 1600);
PAINT GREEN (-3175 1600);
DISPLAY INVISIBLE (-3175 1600);
FORCEPROP 1 LAST BODY_TYPE PLUMBING
J 2
(-2850 1675);
DISPLAY 1.595745 (-2850 1675);
PAINT GREEN (-2850 1675);
DISPLAY INVISIBLE (-2850 1675);
FORCEPROP 2 LAST CDS_LIB mstr_standard
J 0
(-2850 1725);
PAINT MONO (-2850 1725);
DISPLAY INVISIBLE (-2850 1725);
FORCEADD TAP..6
R 2
(-2850 1825);
FORCEPROP 3 LASTPIN (-2900 1825) SIG_NAME M_F_CKE<3>
J 0
(-2890 1835);
DISPLAY 0.659574 (-2890 1835);
PAINT MONO (-2890 1835);
DISPLAY INVISIBLE (-2890 1835);
FORCEPROP 1 LASTPIN (-2900 1825) BN 3
J 2
(-2848 1833);
DISPLAY 0.617021 (-2848 1833);
PAINT PINK (-2848 1833);
FORCEPROP 1 LAST PATH I105
J 2
(-2848 1825);
DISPLAY 0.872340 (-2848 1825);
PAINT GREEN (-2848 1825);
DISPLAY INVISIBLE (-2848 1825);
FORCEPROP 1 LAST HDL_TAP TRUE
J 2
(-3175 1700);
DISPLAY 1.595745 (-3175 1700);
PAINT GREEN (-3175 1700);
DISPLAY INVISIBLE (-3175 1700);
FORCEPROP 1 LAST BODY_TYPE PLUMBING
J 2
(-2850 1775);
DISPLAY 1.595745 (-2850 1775);
PAINT GREEN (-2850 1775);
DISPLAY INVISIBLE (-2850 1775);
FORCEPROP 2 LAST CDS_LIB mstr_standard
J 0
(-2850 1825);
PAINT MONO (-2850 1825);
DISPLAY INVISIBLE (-2850 1825);
FORCEADD TAP..6
R 2
(-2850 1775);
FORCEPROP 3 LASTPIN (-2900 1775) SIG_NAME M_F_CKE<2>
J 0
(-2890 1785);
DISPLAY 0.659574 (-2890 1785);
PAINT MONO (-2890 1785);
DISPLAY INVISIBLE (-2890 1785);
FORCEPROP 1 LASTPIN (-2900 1775) BN 2
J 2
(-2848 1783);
DISPLAY 0.617021 (-2848 1783);
PAINT PINK (-2848 1783);
FORCEPROP 1 LAST PATH I106
J 2
(-2848 1775);
DISPLAY 0.872340 (-2848 1775);
PAINT GREEN (-2848 1775);
DISPLAY INVISIBLE (-2848 1775);
FORCEPROP 1 LAST HDL_TAP TRUE
J 2
(-3175 1650);
DISPLAY 1.595745 (-3175 1650);
PAINT GREEN (-3175 1650);
DISPLAY INVISIBLE (-3175 1650);
FORCEPROP 1 LAST BODY_TYPE PLUMBING
J 2
(-2850 1725);
DISPLAY 1.595745 (-2850 1725);
PAINT GREEN (-2850 1725);
DISPLAY INVISIBLE (-2850 1725);
FORCEPROP 2 LAST CDS_LIB mstr_standard
J 0
(-2850 1775);
PAINT MONO (-2850 1775);
DISPLAY INVISIBLE (-2850 1775);
FORCEADD TAP..6
R 2
(-2850 1925);
FORCEPROP 3 LASTPIN (-2900 1925) SIG_NAME M_F_MA<0>
J 0
(-2890 1935);
DISPLAY 0.659574 (-2890 1935);
PAINT MONO (-2890 1935);
DISPLAY INVISIBLE (-2890 1935);
FORCEPROP 1 LASTPIN (-2900 1925) BN 0
J 2
(-2848 1933);
DISPLAY 0.617021 (-2848 1933);
PAINT PINK (-2848 1933);
FORCEPROP 1 LAST PATH I107
J 2
(-2848 1925);
DISPLAY 0.872340 (-2848 1925);
PAINT GREEN (-2848 1925);
DISPLAY INVISIBLE (-2848 1925);
FORCEPROP 1 LAST HDL_TAP TRUE
J 2
(-3175 1800);
DISPLAY 1.595745 (-3175 1800);
PAINT GREEN (-3175 1800);
DISPLAY INVISIBLE (-3175 1800);
FORCEPROP 1 LAST BODY_TYPE PLUMBING
J 2
(-2850 1875);
DISPLAY 1.595745 (-2850 1875);
PAINT GREEN (-2850 1875);
DISPLAY INVISIBLE (-2850 1875);
FORCEPROP 2 LAST CDS_LIB mstr_standard
J 0
(-2850 1925);
PAINT MONO (-2850 1925);
DISPLAY INVISIBLE (-2850 1925);
FORCEADD TAP..6
R 2
(-2850 1975);
FORCEPROP 3 LASTPIN (-2900 1975) SIG_NAME M_F_MA<1>
J 0
(-2890 1985);
DISPLAY 0.659574 (-2890 1985);
PAINT MONO (-2890 1985);
DISPLAY INVISIBLE (-2890 1985);
FORCEPROP 1 LASTPIN (-2900 1975) BN 1
J 2
(-2848 1983);
DISPLAY 0.617021 (-2848 1983);
PAINT PINK (-2848 1983);
FORCEPROP 1 LAST PATH I108
J 2
(-2848 1975);
DISPLAY 0.872340 (-2848 1975);
PAINT GREEN (-2848 1975);
DISPLAY INVISIBLE (-2848 1975);
FORCEPROP 1 LAST HDL_TAP TRUE
J 2
(-3175 1850);
DISPLAY 1.595745 (-3175 1850);
PAINT GREEN (-3175 1850);
DISPLAY INVISIBLE (-3175 1850);
FORCEPROP 1 LAST BODY_TYPE PLUMBING
J 2
(-2850 1925);
DISPLAY 1.595745 (-2850 1925);
PAINT GREEN (-2850 1925);
DISPLAY INVISIBLE (-2850 1925);
FORCEPROP 2 LAST CDS_LIB mstr_standard
J 0
(-2850 1975);
PAINT MONO (-2850 1975);
DISPLAY INVISIBLE (-2850 1975);
FORCEADD TAP..6
R 2
(-2850 2075);
FORCEPROP 3 LASTPIN (-2900 2075) SIG_NAME M_F_MA<3>
J 0
(-2890 2085);
DISPLAY 0.659574 (-2890 2085);
PAINT MONO (-2890 2085);
DISPLAY INVISIBLE (-2890 2085);
FORCEPROP 1 LASTPIN (-2900 2075) BN 3
J 2
(-2848 2083);
DISPLAY 0.617021 (-2848 2083);
PAINT PINK (-2848 2083);
FORCEPROP 1 LAST PATH I109
J 2
(-2848 2075);
DISPLAY 0.872340 (-2848 2075);
PAINT GREEN (-2848 2075);
DISPLAY INVISIBLE (-2848 2075);
FORCEPROP 1 LAST HDL_TAP TRUE
J 2
(-3175 1950);
DISPLAY 1.595745 (-3175 1950);
PAINT GREEN (-3175 1950);
DISPLAY INVISIBLE (-3175 1950);
FORCEPROP 1 LAST BODY_TYPE PLUMBING
J 2
(-2850 2025);
DISPLAY 1.595745 (-2850 2025);
PAINT GREEN (-2850 2025);
DISPLAY INVISIBLE (-2850 2025);
FORCEPROP 2 LAST CDS_LIB mstr_standard
J 0
(-2850 2075);
PAINT MONO (-2850 2075);
DISPLAY INVISIBLE (-2850 2075);
FORCEADD TAP..6
(-5575 925);
FORCEPROP 3 LASTPIN (-5525 925) SIG_NAME M_F_CLK_DP<2>
J 0
(-5515 935);
DISPLAY 0.659574 (-5515 935);
PAINT MONO (-5515 935);
DISPLAY INVISIBLE (-5515 935);
FORCEPROP 1 LASTPIN (-5525 925) BN 2
J 0
(-5577 933);
DISPLAY 0.617021 (-5577 933);
PAINT PINK (-5577 933);
FORCEPROP 1 LAST PATH I11
J 0
(-5577 925);
DISPLAY 0.872340 (-5577 925);
PAINT GREEN (-5577 925);
DISPLAY INVISIBLE (-5577 925);
FORCEPROP 1 LAST HDL_TAP TRUE
J 0
(-5250 800);
DISPLAY 1.595745 (-5250 800);
PAINT GREEN (-5250 800);
DISPLAY INVISIBLE (-5250 800);
FORCEPROP 1 LAST BODY_TYPE PLUMBING
J 0
(-5575 875);
DISPLAY 1.595745 (-5575 875);
PAINT GREEN (-5575 875);
DISPLAY INVISIBLE (-5575 875);
FORCEPROP 2 LAST CDS_LIB mstr_standard
J 0
(-5575 925);
PAINT MONO (-5575 925);
DISPLAY INVISIBLE (-5575 925);
FORCEADD TAP..6
R 2
(-2850 2025);
FORCEPROP 3 LASTPIN (-2900 2025) SIG_NAME M_F_MA<2>
J 0
(-2890 2035);
DISPLAY 0.659574 (-2890 2035);
PAINT MONO (-2890 2035);
DISPLAY INVISIBLE (-2890 2035);
FORCEPROP 1 LASTPIN (-2900 2025) BN 2
J 2
(-2848 2033);
DISPLAY 0.617021 (-2848 2033);
PAINT PINK (-2848 2033);
FORCEPROP 1 LAST PATH I110
J 2
(-2848 2025);
DISPLAY 0.872340 (-2848 2025);
PAINT GREEN (-2848 2025);
DISPLAY INVISIBLE (-2848 2025);
FORCEPROP 1 LAST HDL_TAP TRUE
J 2
(-3175 1900);
DISPLAY 1.595745 (-3175 1900);
PAINT GREEN (-3175 1900);
DISPLAY INVISIBLE (-3175 1900);
FORCEPROP 1 LAST BODY_TYPE PLUMBING
J 2
(-2850 1975);
DISPLAY 1.595745 (-2850 1975);
PAINT GREEN (-2850 1975);
DISPLAY INVISIBLE (-2850 1975);
FORCEPROP 2 LAST CDS_LIB mstr_standard
J 0
(-2850 2025);
PAINT MONO (-2850 2025);
DISPLAY INVISIBLE (-2850 2025);
FORCEADD TAP..6
R 2
(-2850 2125);
FORCEPROP 3 LASTPIN (-2900 2125) SIG_NAME M_F_MA<4>
J 0
(-2890 2135);
DISPLAY 0.659574 (-2890 2135);
PAINT MONO (-2890 2135);
DISPLAY INVISIBLE (-2890 2135);
FORCEPROP 1 LASTPIN (-2900 2125) BN 4
J 2
(-2848 2133);
DISPLAY 0.617021 (-2848 2133);
PAINT PINK (-2848 2133);
FORCEPROP 1 LAST PATH I111
J 2
(-2848 2125);
DISPLAY 0.872340 (-2848 2125);
PAINT GREEN (-2848 2125);
DISPLAY INVISIBLE (-2848 2125);
FORCEPROP 1 LAST HDL_TAP TRUE
J 2
(-3175 2000);
DISPLAY 1.595745 (-3175 2000);
PAINT GREEN (-3175 2000);
DISPLAY INVISIBLE (-3175 2000);
FORCEPROP 1 LAST BODY_TYPE PLUMBING
J 2
(-2850 2075);
DISPLAY 1.595745 (-2850 2075);
PAINT GREEN (-2850 2075);
DISPLAY INVISIBLE (-2850 2075);
FORCEPROP 2 LAST CDS_LIB mstr_standard
J 0
(-2850 2125);
PAINT MONO (-2850 2125);
DISPLAY INVISIBLE (-2850 2125);
FORCEADD TAP..6
R 2
(-2850 2175);
FORCEPROP 3 LASTPIN (-2900 2175) SIG_NAME M_F_MA<5>
J 0
(-2890 2185);
DISPLAY 0.659574 (-2890 2185);
PAINT MONO (-2890 2185);
DISPLAY INVISIBLE (-2890 2185);
FORCEPROP 1 LASTPIN (-2900 2175) BN 5
J 2
(-2848 2183);
DISPLAY 0.617021 (-2848 2183);
PAINT PINK (-2848 2183);
FORCEPROP 1 LAST PATH I112
J 2
(-2848 2175);
DISPLAY 0.872340 (-2848 2175);
PAINT GREEN (-2848 2175);
DISPLAY INVISIBLE (-2848 2175);
FORCEPROP 1 LAST HDL_TAP TRUE
J 2
(-3175 2050);
DISPLAY 1.595745 (-3175 2050);
PAINT GREEN (-3175 2050);
DISPLAY INVISIBLE (-3175 2050);
FORCEPROP 1 LAST BODY_TYPE PLUMBING
J 2
(-2850 2125);
DISPLAY 1.595745 (-2850 2125);
PAINT GREEN (-2850 2125);
DISPLAY INVISIBLE (-2850 2125);
FORCEPROP 2 LAST CDS_LIB mstr_standard
J 0
(-2850 2175);
PAINT MONO (-2850 2175);
DISPLAY INVISIBLE (-2850 2175);
FORCEADD TAP..6
R 2
(-2850 2225);
FORCEPROP 3 LASTPIN (-2900 2225) SIG_NAME M_F_MA<6>
J 0
(-2890 2235);
DISPLAY 0.659574 (-2890 2235);
PAINT MONO (-2890 2235);
DISPLAY INVISIBLE (-2890 2235);
FORCEPROP 1 LASTPIN (-2900 2225) BN 6
J 2
(-2848 2233);
DISPLAY 0.617021 (-2848 2233);
PAINT PINK (-2848 2233);
FORCEPROP 1 LAST PATH I113
J 2
(-2848 2225);
DISPLAY 0.872340 (-2848 2225);
PAINT GREEN (-2848 2225);
DISPLAY INVISIBLE (-2848 2225);
FORCEPROP 1 LAST HDL_TAP TRUE
J 2
(-3175 2100);
DISPLAY 1.595745 (-3175 2100);
PAINT GREEN (-3175 2100);
DISPLAY INVISIBLE (-3175 2100);
FORCEPROP 1 LAST BODY_TYPE PLUMBING
J 2
(-2850 2175);
DISPLAY 1.595745 (-2850 2175);
PAINT GREEN (-2850 2175);
DISPLAY INVISIBLE (-2850 2175);
FORCEPROP 2 LAST CDS_LIB mstr_standard
J 0
(-2850 2225);
PAINT MONO (-2850 2225);
DISPLAY INVISIBLE (-2850 2225);
FORCEADD TAP..6
R 2
(-2850 2375);
FORCEPROP 3 LASTPIN (-2900 2375) SIG_NAME M_F_MA<9>
J 0
(-2890 2385);
DISPLAY 0.659574 (-2890 2385);
PAINT MONO (-2890 2385);
DISPLAY INVISIBLE (-2890 2385);
FORCEPROP 1 LASTPIN (-2900 2375) BN 9
J 2
(-2848 2383);
DISPLAY 0.617021 (-2848 2383);
PAINT PINK (-2848 2383);
FORCEPROP 1 LAST PATH I114
J 2
(-2848 2375);
DISPLAY 0.872340 (-2848 2375);
PAINT GREEN (-2848 2375);
DISPLAY INVISIBLE (-2848 2375);
FORCEPROP 1 LAST HDL_TAP TRUE
J 2
(-3175 2250);
DISPLAY 1.595745 (-3175 2250);
PAINT GREEN (-3175 2250);
DISPLAY INVISIBLE (-3175 2250);
FORCEPROP 1 LAST BODY_TYPE PLUMBING
J 2
(-2850 2325);
DISPLAY 1.595745 (-2850 2325);
PAINT GREEN (-2850 2325);
DISPLAY INVISIBLE (-2850 2325);
FORCEPROP 2 LAST CDS_LIB mstr_standard
J 0
(-2850 2375);
PAINT MONO (-2850 2375);
DISPLAY INVISIBLE (-2850 2375);
FORCEADD TAP..6
R 2
(-2850 2325);
FORCEPROP 3 LASTPIN (-2900 2325) SIG_NAME M_F_MA<8>
J 0
(-2890 2335);
DISPLAY 0.659574 (-2890 2335);
PAINT MONO (-2890 2335);
DISPLAY INVISIBLE (-2890 2335);
FORCEPROP 1 LASTPIN (-2900 2325) BN 8
J 2
(-2848 2333);
DISPLAY 0.617021 (-2848 2333);
PAINT PINK (-2848 2333);
FORCEPROP 1 LAST PATH I115
J 2
(-2848 2325);
DISPLAY 0.872340 (-2848 2325);
PAINT GREEN (-2848 2325);
DISPLAY INVISIBLE (-2848 2325);
FORCEPROP 1 LAST HDL_TAP TRUE
J 2
(-3175 2200);
DISPLAY 1.595745 (-3175 2200);
PAINT GREEN (-3175 2200);
DISPLAY INVISIBLE (-3175 2200);
FORCEPROP 1 LAST BODY_TYPE PLUMBING
J 2
(-2850 2275);
DISPLAY 1.595745 (-2850 2275);
PAINT GREEN (-2850 2275);
DISPLAY INVISIBLE (-2850 2275);
FORCEPROP 2 LAST CDS_LIB mstr_standard
J 0
(-2850 2325);
PAINT MONO (-2850 2325);
DISPLAY INVISIBLE (-2850 2325);
FORCEADD TAP..6
R 2
(-2850 2275);
FORCEPROP 3 LASTPIN (-2900 2275) SIG_NAME M_F_MA<7>
J 0
(-2890 2285);
DISPLAY 0.659574 (-2890 2285);
PAINT MONO (-2890 2285);
DISPLAY INVISIBLE (-2890 2285);
FORCEPROP 1 LASTPIN (-2900 2275) BN 7
J 2
(-2848 2283);
DISPLAY 0.617021 (-2848 2283);
PAINT PINK (-2848 2283);
FORCEPROP 1 LAST PATH I116
J 2
(-2848 2275);
DISPLAY 0.872340 (-2848 2275);
PAINT GREEN (-2848 2275);
DISPLAY INVISIBLE (-2848 2275);
FORCEPROP 1 LAST HDL_TAP TRUE
J 2
(-3175 2150);
DISPLAY 1.595745 (-3175 2150);
PAINT GREEN (-3175 2150);
DISPLAY INVISIBLE (-3175 2150);
FORCEPROP 1 LAST BODY_TYPE PLUMBING
J 2
(-2850 2225);
DISPLAY 1.595745 (-2850 2225);
PAINT GREEN (-2850 2225);
DISPLAY INVISIBLE (-2850 2225);
FORCEPROP 2 LAST CDS_LIB mstr_standard
J 0
(-2850 2275);
PAINT MONO (-2850 2275);
DISPLAY INVISIBLE (-2850 2275);
FORCEADD TAP..6
R 2
(-2850 2475);
FORCEPROP 3 LASTPIN (-2900 2475) SIG_NAME M_F_MA<11>
J 0
(-2890 2485);
DISPLAY 0.659574 (-2890 2485);
PAINT MONO (-2890 2485);
DISPLAY INVISIBLE (-2890 2485);
FORCEPROP 1 LASTPIN (-2900 2475) BN 11
J 2
(-2848 2483);
DISPLAY 0.617021 (-2848 2483);
PAINT PINK (-2848 2483);
FORCEPROP 1 LAST PATH I117
J 2
(-2848 2475);
DISPLAY 0.872340 (-2848 2475);
PAINT GREEN (-2848 2475);
DISPLAY INVISIBLE (-2848 2475);
FORCEPROP 1 LAST HDL_TAP TRUE
J 2
(-3175 2350);
DISPLAY 1.595745 (-3175 2350);
PAINT GREEN (-3175 2350);
DISPLAY INVISIBLE (-3175 2350);
FORCEPROP 1 LAST BODY_TYPE PLUMBING
J 2
(-2850 2425);
DISPLAY 1.595745 (-2850 2425);
PAINT GREEN (-2850 2425);
DISPLAY INVISIBLE (-2850 2425);
FORCEPROP 2 LAST CDS_LIB mstr_standard
J 0
(-2850 2475);
PAINT MONO (-2850 2475);
DISPLAY INVISIBLE (-2850 2475);
FORCEADD TAP..6
R 2
(-2850 2425);
FORCEPROP 3 LASTPIN (-2900 2425) SIG_NAME M_F_MA<10>
J 0
(-2890 2435);
DISPLAY 0.659574 (-2890 2435);
PAINT MONO (-2890 2435);
DISPLAY INVISIBLE (-2890 2435);
FORCEPROP 1 LASTPIN (-2900 2425) BN 10
J 2
(-2848 2433);
DISPLAY 0.617021 (-2848 2433);
PAINT PINK (-2848 2433);
FORCEPROP 1 LAST PATH I118
J 2
(-2848 2425);
DISPLAY 0.872340 (-2848 2425);
PAINT GREEN (-2848 2425);
DISPLAY INVISIBLE (-2848 2425);
FORCEPROP 1 LAST HDL_TAP TRUE
J 2
(-3175 2300);
DISPLAY 1.595745 (-3175 2300);
PAINT GREEN (-3175 2300);
DISPLAY INVISIBLE (-3175 2300);
FORCEPROP 1 LAST BODY_TYPE PLUMBING
J 2
(-2850 2375);
DISPLAY 1.595745 (-2850 2375);
PAINT GREEN (-2850 2375);
DISPLAY INVISIBLE (-2850 2375);
FORCEPROP 2 LAST CDS_LIB mstr_standard
J 0
(-2850 2425);
PAINT MONO (-2850 2425);
DISPLAY INVISIBLE (-2850 2425);
FORCEADD TAP..6
R 2
(-2850 2525);
FORCEPROP 3 LASTPIN (-2900 2525) SIG_NAME M_F_MA<12>
J 0
(-2890 2535);
DISPLAY 0.659574 (-2890 2535);
PAINT MONO (-2890 2535);
DISPLAY INVISIBLE (-2890 2535);
FORCEPROP 1 LASTPIN (-2900 2525) BN 12
J 2
(-2848 2533);
DISPLAY 0.617021 (-2848 2533);
PAINT PINK (-2848 2533);
FORCEPROP 1 LAST PATH I119
J 2
(-2848 2525);
DISPLAY 0.872340 (-2848 2525);
PAINT GREEN (-2848 2525);
DISPLAY INVISIBLE (-2848 2525);
FORCEPROP 1 LAST HDL_TAP TRUE
J 2
(-3175 2400);
DISPLAY 1.595745 (-3175 2400);
PAINT GREEN (-3175 2400);
DISPLAY INVISIBLE (-3175 2400);
FORCEPROP 1 LAST BODY_TYPE PLUMBING
J 2
(-2850 2475);
DISPLAY 1.595745 (-2850 2475);
PAINT GREEN (-2850 2475);
DISPLAY INVISIBLE (-2850 2475);
FORCEPROP 2 LAST CDS_LIB mstr_standard
J 0
(-2850 2525);
PAINT MONO (-2850 2525);
DISPLAY INVISIBLE (-2850 2525);
FORCEADD TAP..6
(-5575 975);
FORCEPROP 3 LASTPIN (-5525 975) SIG_NAME M_F_CLK_DP<3>
J 0
(-5515 985);
DISPLAY 0.659574 (-5515 985);
PAINT MONO (-5515 985);
DISPLAY INVISIBLE (-5515 985);
FORCEPROP 1 LASTPIN (-5525 975) BN 3
J 0
(-5577 983);
DISPLAY 0.617021 (-5577 983);
PAINT PINK (-5577 983);
FORCEPROP 1 LAST PATH I12
J 0
(-5577 975);
DISPLAY 0.872340 (-5577 975);
PAINT GREEN (-5577 975);
DISPLAY INVISIBLE (-5577 975);
FORCEPROP 1 LAST HDL_TAP TRUE
J 0
(-5250 850);
DISPLAY 1.595745 (-5250 850);
PAINT GREEN (-5250 850);
DISPLAY INVISIBLE (-5250 850);
FORCEPROP 1 LAST BODY_TYPE PLUMBING
J 0
(-5575 925);
DISPLAY 1.595745 (-5575 925);
PAINT GREEN (-5575 925);
DISPLAY INVISIBLE (-5575 925);
FORCEPROP 2 LAST CDS_LIB mstr_standard
J 0
(-5575 975);
PAINT MONO (-5575 975);
DISPLAY INVISIBLE (-5575 975);
FORCEADD TAP..6
R 2
(-2850 2575);
FORCEPROP 3 LASTPIN (-2900 2575) SIG_NAME M_F_MA<13>
J 0
(-2890 2585);
DISPLAY 0.659574 (-2890 2585);
PAINT MONO (-2890 2585);
DISPLAY INVISIBLE (-2890 2585);
FORCEPROP 1 LASTPIN (-2900 2575) BN 13
J 2
(-2848 2583);
DISPLAY 0.617021 (-2848 2583);
PAINT PINK (-2848 2583);
FORCEPROP 1 LAST PATH I120
J 2
(-2848 2575);
DISPLAY 0.872340 (-2848 2575);
PAINT GREEN (-2848 2575);
DISPLAY INVISIBLE (-2848 2575);
FORCEPROP 1 LAST HDL_TAP TRUE
J 2
(-3175 2450);
DISPLAY 1.595745 (-3175 2450);
PAINT GREEN (-3175 2450);
DISPLAY INVISIBLE (-3175 2450);
FORCEPROP 1 LAST BODY_TYPE PLUMBING
J 2
(-2850 2525);
DISPLAY 1.595745 (-2850 2525);
PAINT GREEN (-2850 2525);
DISPLAY INVISIBLE (-2850 2525);
FORCEPROP 2 LAST CDS_LIB mstr_standard
J 0
(-2850 2575);
PAINT MONO (-2850 2575);
DISPLAY INVISIBLE (-2850 2575);
FORCEADD TAP..6
R 2
(-2850 2625);
FORCEPROP 3 LASTPIN (-2900 2625) SIG_NAME M_F_MA<14>
J 0
(-2890 2635);
DISPLAY 0.659574 (-2890 2635);
PAINT MONO (-2890 2635);
DISPLAY INVISIBLE (-2890 2635);
FORCEPROP 1 LASTPIN (-2900 2625) BN 14
J 2
(-2848 2633);
DISPLAY 0.617021 (-2848 2633);
PAINT PINK (-2848 2633);
FORCEPROP 1 LAST PATH I121
J 2
(-2848 2625);
DISPLAY 0.872340 (-2848 2625);
PAINT GREEN (-2848 2625);
DISPLAY INVISIBLE (-2848 2625);
FORCEPROP 1 LAST HDL_TAP TRUE
J 2
(-3175 2500);
DISPLAY 1.595745 (-3175 2500);
PAINT GREEN (-3175 2500);
DISPLAY INVISIBLE (-3175 2500);
FORCEPROP 1 LAST BODY_TYPE PLUMBING
J 2
(-2850 2575);
DISPLAY 1.595745 (-2850 2575);
PAINT GREEN (-2850 2575);
DISPLAY INVISIBLE (-2850 2575);
FORCEPROP 2 LAST CDS_LIB mstr_standard
J 0
(-2850 2625);
PAINT MONO (-2850 2625);
DISPLAY INVISIBLE (-2850 2625);
FORCEADD TAP..6
R 2
(-2850 2725);
FORCEPROP 3 LASTPIN (-2900 2725) SIG_NAME M_F_MA<16>
J 0
(-2890 2735);
DISPLAY 0.659574 (-2890 2735);
PAINT MONO (-2890 2735);
DISPLAY INVISIBLE (-2890 2735);
FORCEPROP 1 LASTPIN (-2900 2725) BN 16
J 2
(-2848 2733);
DISPLAY 0.617021 (-2848 2733);
PAINT PINK (-2848 2733);
FORCEPROP 1 LAST PATH I122
J 2
(-2848 2725);
DISPLAY 0.872340 (-2848 2725);
PAINT GREEN (-2848 2725);
DISPLAY INVISIBLE (-2848 2725);
FORCEPROP 1 LAST HDL_TAP TRUE
J 2
(-3175 2600);
DISPLAY 1.595745 (-3175 2600);
PAINT GREEN (-3175 2600);
DISPLAY INVISIBLE (-3175 2600);
FORCEPROP 1 LAST BODY_TYPE PLUMBING
J 2
(-2850 2675);
DISPLAY 1.595745 (-2850 2675);
PAINT GREEN (-2850 2675);
DISPLAY INVISIBLE (-2850 2675);
FORCEPROP 2 LAST CDS_LIB mstr_standard
J 0
(-2850 2725);
PAINT MONO (-2850 2725);
DISPLAY INVISIBLE (-2850 2725);
FORCEADD TAP..6
R 2
(-2850 2675);
FORCEPROP 3 LASTPIN (-2900 2675) SIG_NAME M_F_MA<15>
J 0
(-2890 2685);
DISPLAY 0.659574 (-2890 2685);
PAINT MONO (-2890 2685);
DISPLAY INVISIBLE (-2890 2685);
FORCEPROP 1 LASTPIN (-2900 2675) BN 15
J 2
(-2848 2683);
DISPLAY 0.617021 (-2848 2683);
PAINT PINK (-2848 2683);
FORCEPROP 1 LAST PATH I123
J 2
(-2848 2675);
DISPLAY 0.872340 (-2848 2675);
PAINT GREEN (-2848 2675);
DISPLAY INVISIBLE (-2848 2675);
FORCEPROP 1 LAST HDL_TAP TRUE
J 2
(-3175 2550);
DISPLAY 1.595745 (-3175 2550);
PAINT GREEN (-3175 2550);
DISPLAY INVISIBLE (-3175 2550);
FORCEPROP 1 LAST BODY_TYPE PLUMBING
J 2
(-2850 2625);
DISPLAY 1.595745 (-2850 2625);
PAINT GREEN (-2850 2625);
DISPLAY INVISIBLE (-2850 2625);
FORCEPROP 2 LAST CDS_LIB mstr_standard
J 0
(-2850 2675);
PAINT MONO (-2850 2675);
DISPLAY INVISIBLE (-2850 2675);
FORCEADD TAP..6
R 2
(-2850 2775);
FORCEPROP 3 LASTPIN (-2900 2775) SIG_NAME M_F_MA<17>
J 0
(-2890 2785);
DISPLAY 0.659574 (-2890 2785);
PAINT MONO (-2890 2785);
DISPLAY INVISIBLE (-2890 2785);
FORCEPROP 1 LASTPIN (-2900 2775) BN 17
J 2
(-2848 2783);
DISPLAY 0.617021 (-2848 2783);
PAINT PINK (-2848 2783);
FORCEPROP 1 LAST PATH I124
J 2
(-2848 2775);
DISPLAY 0.872340 (-2848 2775);
PAINT GREEN (-2848 2775);
DISPLAY INVISIBLE (-2848 2775);
FORCEPROP 1 LAST HDL_TAP TRUE
J 2
(-3175 2650);
DISPLAY 1.595745 (-3175 2650);
PAINT GREEN (-3175 2650);
DISPLAY INVISIBLE (-3175 2650);
FORCEPROP 1 LAST BODY_TYPE PLUMBING
J 2
(-2850 2725);
DISPLAY 1.595745 (-2850 2725);
PAINT GREEN (-2850 2725);
DISPLAY INVISIBLE (-2850 2725);
FORCEPROP 2 LAST CDS_LIB mstr_standard
J 0
(-2850 2775);
PAINT MONO (-2850 2775);
DISPLAY INVISIBLE (-2850 2775);
FORCEADD TAP..6
R 2
(-2850 2875);
FORCEPROP 3 LASTPIN (-2900 2875) SIG_NAME M_F_DQS_DN<0>
J 0
(-2890 2885);
DISPLAY 0.659574 (-2890 2885);
PAINT MONO (-2890 2885);
DISPLAY INVISIBLE (-2890 2885);
FORCEPROP 1 LASTPIN (-2900 2875) BN 0
J 2
(-2848 2883);
DISPLAY 0.617021 (-2848 2883);
PAINT PINK (-2848 2883);
FORCEPROP 1 LAST PATH I125
J 2
(-2848 2875);
DISPLAY 0.872340 (-2848 2875);
PAINT GREEN (-2848 2875);
DISPLAY INVISIBLE (-2848 2875);
FORCEPROP 1 LAST HDL_TAP TRUE
J 2
(-3175 2750);
DISPLAY 1.595745 (-3175 2750);
PAINT GREEN (-3175 2750);
DISPLAY INVISIBLE (-3175 2750);
FORCEPROP 1 LAST BODY_TYPE PLUMBING
J 2
(-2850 2825);
DISPLAY 1.595745 (-2850 2825);
PAINT GREEN (-2850 2825);
DISPLAY INVISIBLE (-2850 2825);
FORCEPROP 2 LAST CDS_LIB mstr_standard
J 0
(-2850 2875);
PAINT MONO (-2850 2875);
DISPLAY INVISIBLE (-2850 2875);
FORCEADD TAP..6
R 2
(-2850 2975);
FORCEPROP 3 LASTPIN (-2900 2975) SIG_NAME M_F_DQS_DN<2>
J 0
(-2890 2985);
DISPLAY 0.659574 (-2890 2985);
PAINT MONO (-2890 2985);
DISPLAY INVISIBLE (-2890 2985);
FORCEPROP 1 LASTPIN (-2900 2975) BN 2
J 2
(-2848 2983);
DISPLAY 0.617021 (-2848 2983);
PAINT PINK (-2848 2983);
FORCEPROP 1 LAST PATH I126
J 2
(-2848 2975);
DISPLAY 0.872340 (-2848 2975);
PAINT GREEN (-2848 2975);
DISPLAY INVISIBLE (-2848 2975);
FORCEPROP 1 LAST HDL_TAP TRUE
J 2
(-3175 2850);
DISPLAY 1.595745 (-3175 2850);
PAINT GREEN (-3175 2850);
DISPLAY INVISIBLE (-3175 2850);
FORCEPROP 1 LAST BODY_TYPE PLUMBING
J 2
(-2850 2925);
DISPLAY 1.595745 (-2850 2925);
PAINT GREEN (-2850 2925);
DISPLAY INVISIBLE (-2850 2925);
FORCEPROP 2 LAST CDS_LIB mstr_standard
J 0
(-2850 2975);
PAINT MONO (-2850 2975);
DISPLAY INVISIBLE (-2850 2975);
FORCEADD TAP..6
R 2
(-2850 2925);
FORCEPROP 3 LASTPIN (-2900 2925) SIG_NAME M_F_DQS_DN<1>
J 0
(-2890 2935);
DISPLAY 0.659574 (-2890 2935);
PAINT MONO (-2890 2935);
DISPLAY INVISIBLE (-2890 2935);
FORCEPROP 1 LASTPIN (-2900 2925) BN 1
J 2
(-2848 2933);
DISPLAY 0.617021 (-2848 2933);
PAINT PINK (-2848 2933);
FORCEPROP 1 LAST PATH I127
J 2
(-2848 2925);
DISPLAY 0.872340 (-2848 2925);
PAINT GREEN (-2848 2925);
DISPLAY INVISIBLE (-2848 2925);
FORCEPROP 1 LAST HDL_TAP TRUE
J 2
(-3175 2800);
DISPLAY 1.595745 (-3175 2800);
PAINT GREEN (-3175 2800);
DISPLAY INVISIBLE (-3175 2800);
FORCEPROP 1 LAST BODY_TYPE PLUMBING
J 2
(-2850 2875);
DISPLAY 1.595745 (-2850 2875);
PAINT GREEN (-2850 2875);
DISPLAY INVISIBLE (-2850 2875);
FORCEPROP 2 LAST CDS_LIB mstr_standard
J 0
(-2850 2925);
PAINT MONO (-2850 2925);
DISPLAY INVISIBLE (-2850 2925);
FORCEADD TAP..6
R 2
(-2850 3025);
FORCEPROP 3 LASTPIN (-2900 3025) SIG_NAME M_F_DQS_DN<3>
J 0
(-2890 3035);
DISPLAY 0.659574 (-2890 3035);
PAINT MONO (-2890 3035);
DISPLAY INVISIBLE (-2890 3035);
FORCEPROP 1 LASTPIN (-2900 3025) BN 3
J 2
(-2848 3033);
DISPLAY 0.617021 (-2848 3033);
PAINT PINK (-2848 3033);
FORCEPROP 1 LAST PATH I128
J 2
(-2848 3025);
DISPLAY 0.872340 (-2848 3025);
PAINT GREEN (-2848 3025);
DISPLAY INVISIBLE (-2848 3025);
FORCEPROP 1 LAST HDL_TAP TRUE
J 2
(-3175 2900);
DISPLAY 1.595745 (-3175 2900);
PAINT GREEN (-3175 2900);
DISPLAY INVISIBLE (-3175 2900);
FORCEPROP 1 LAST BODY_TYPE PLUMBING
J 2
(-2850 2975);
DISPLAY 1.595745 (-2850 2975);
PAINT GREEN (-2850 2975);
DISPLAY INVISIBLE (-2850 2975);
FORCEPROP 2 LAST CDS_LIB mstr_standard
J 0
(-2850 3025);
PAINT MONO (-2850 3025);
DISPLAY INVISIBLE (-2850 3025);
FORCEADD TAP..6
R 2
(-2850 3075);
FORCEPROP 3 LASTPIN (-2900 3075) SIG_NAME M_F_DQS_DN<4>
J 0
(-2890 3085);
DISPLAY 0.659574 (-2890 3085);
PAINT MONO (-2890 3085);
DISPLAY INVISIBLE (-2890 3085);
FORCEPROP 1 LASTPIN (-2900 3075) BN 4
J 2
(-2848 3083);
DISPLAY 0.617021 (-2848 3083);
PAINT PINK (-2848 3083);
FORCEPROP 1 LAST PATH I129
J 2
(-2848 3075);
DISPLAY 0.872340 (-2848 3075);
PAINT GREEN (-2848 3075);
DISPLAY INVISIBLE (-2848 3075);
FORCEPROP 1 LAST HDL_TAP TRUE
J 2
(-3175 2950);
DISPLAY 1.595745 (-3175 2950);
PAINT GREEN (-3175 2950);
DISPLAY INVISIBLE (-3175 2950);
FORCEPROP 1 LAST BODY_TYPE PLUMBING
J 2
(-2850 3025);
DISPLAY 1.595745 (-2850 3025);
PAINT GREEN (-2850 3025);
DISPLAY INVISIBLE (-2850 3025);
FORCEPROP 2 LAST CDS_LIB mstr_standard
J 0
(-2850 3075);
PAINT MONO (-2850 3075);
DISPLAY INVISIBLE (-2850 3075);
FORCEADD TAP..6
(-5575 1075);
FORCEPROP 3 LASTPIN (-5525 1075) SIG_NAME M_F_ECC<0>
J 0
(-5515 1085);
DISPLAY 0.659574 (-5515 1085);
PAINT MONO (-5515 1085);
DISPLAY INVISIBLE (-5515 1085);
FORCEPROP 1 LASTPIN (-5525 1075) BN 0
J 0
(-5577 1083);
DISPLAY 0.617021 (-5577 1083);
PAINT PINK (-5577 1083);
FORCEPROP 1 LAST PATH I13
J 0
(-5577 1075);
DISPLAY 0.872340 (-5577 1075);
PAINT GREEN (-5577 1075);
DISPLAY INVISIBLE (-5577 1075);
FORCEPROP 1 LAST HDL_TAP TRUE
J 0
(-5250 950);
DISPLAY 1.595745 (-5250 950);
PAINT GREEN (-5250 950);
DISPLAY INVISIBLE (-5250 950);
FORCEPROP 1 LAST BODY_TYPE PLUMBING
J 0
(-5575 1025);
DISPLAY 1.595745 (-5575 1025);
PAINT GREEN (-5575 1025);
DISPLAY INVISIBLE (-5575 1025);
FORCEPROP 2 LAST CDS_LIB mstr_standard
J 0
(-5575 1075);
PAINT MONO (-5575 1075);
DISPLAY INVISIBLE (-5575 1075);
FORCEADD TAP..6
R 2
(-2850 3125);
FORCEPROP 3 LASTPIN (-2900 3125) SIG_NAME M_F_DQS_DN<5>
J 0
(-2890 3135);
DISPLAY 0.659574 (-2890 3135);
PAINT MONO (-2890 3135);
DISPLAY INVISIBLE (-2890 3135);
FORCEPROP 1 LASTPIN (-2900 3125) BN 5
J 2
(-2848 3133);
DISPLAY 0.617021 (-2848 3133);
PAINT PINK (-2848 3133);
FORCEPROP 1 LAST PATH I130
J 2
(-2848 3125);
DISPLAY 0.872340 (-2848 3125);
PAINT GREEN (-2848 3125);
DISPLAY INVISIBLE (-2848 3125);
FORCEPROP 1 LAST HDL_TAP TRUE
J 2
(-3175 3000);
DISPLAY 1.595745 (-3175 3000);
PAINT GREEN (-3175 3000);
DISPLAY INVISIBLE (-3175 3000);
FORCEPROP 1 LAST BODY_TYPE PLUMBING
J 2
(-2850 3075);
DISPLAY 1.595745 (-2850 3075);
PAINT GREEN (-2850 3075);
DISPLAY INVISIBLE (-2850 3075);
FORCEPROP 2 LAST CDS_LIB mstr_standard
J 0
(-2850 3125);
PAINT MONO (-2850 3125);
DISPLAY INVISIBLE (-2850 3125);
FORCEADD TAP..6
R 2
(-2850 3225);
FORCEPROP 3 LASTPIN (-2900 3225) SIG_NAME M_F_DQS_DN<7>
J 0
(-2890 3235);
DISPLAY 0.659574 (-2890 3235);
PAINT MONO (-2890 3235);
DISPLAY INVISIBLE (-2890 3235);
FORCEPROP 1 LASTPIN (-2900 3225) BN 7
J 2
(-2848 3233);
DISPLAY 0.617021 (-2848 3233);
PAINT PINK (-2848 3233);
FORCEPROP 1 LAST PATH I131
J 2
(-2848 3225);
DISPLAY 0.872340 (-2848 3225);
PAINT GREEN (-2848 3225);
DISPLAY INVISIBLE (-2848 3225);
FORCEPROP 1 LAST HDL_TAP TRUE
J 2
(-3175 3100);
DISPLAY 1.595745 (-3175 3100);
PAINT GREEN (-3175 3100);
DISPLAY INVISIBLE (-3175 3100);
FORCEPROP 1 LAST BODY_TYPE PLUMBING
J 2
(-2850 3175);
DISPLAY 1.595745 (-2850 3175);
PAINT GREEN (-2850 3175);
DISPLAY INVISIBLE (-2850 3175);
FORCEPROP 2 LAST CDS_LIB mstr_standard
J 0
(-2850 3225);
PAINT MONO (-2850 3225);
DISPLAY INVISIBLE (-2850 3225);
FORCEADD TAP..6
R 2
(-2850 3175);
FORCEPROP 3 LASTPIN (-2900 3175) SIG_NAME M_F_DQS_DN<6>
J 0
(-2890 3185);
DISPLAY 0.659574 (-2890 3185);
PAINT MONO (-2890 3185);
DISPLAY INVISIBLE (-2890 3185);
FORCEPROP 1 LASTPIN (-2900 3175) BN 6
J 2
(-2848 3183);
DISPLAY 0.617021 (-2848 3183);
PAINT PINK (-2848 3183);
FORCEPROP 1 LAST PATH I132
J 2
(-2848 3175);
DISPLAY 0.872340 (-2848 3175);
PAINT GREEN (-2848 3175);
DISPLAY INVISIBLE (-2848 3175);
FORCEPROP 1 LAST HDL_TAP TRUE
J 2
(-3175 3050);
DISPLAY 1.595745 (-3175 3050);
PAINT GREEN (-3175 3050);
DISPLAY INVISIBLE (-3175 3050);
FORCEPROP 1 LAST BODY_TYPE PLUMBING
J 2
(-2850 3125);
DISPLAY 1.595745 (-2850 3125);
PAINT GREEN (-2850 3125);
DISPLAY INVISIBLE (-2850 3125);
FORCEPROP 2 LAST CDS_LIB mstr_standard
J 0
(-2850 3175);
PAINT MONO (-2850 3175);
DISPLAY INVISIBLE (-2850 3175);
FORCEADD TAP..6
R 2
(-2850 3275);
FORCEPROP 3 LASTPIN (-2900 3275) SIG_NAME M_F_DQS_DN<8>
J 0
(-2890 3285);
DISPLAY 0.659574 (-2890 3285);
PAINT MONO (-2890 3285);
DISPLAY INVISIBLE (-2890 3285);
FORCEPROP 1 LASTPIN (-2900 3275) BN 8
J 2
(-2848 3283);
DISPLAY 0.617021 (-2848 3283);
PAINT PINK (-2848 3283);
FORCEPROP 1 LAST PATH I133
J 2
(-2848 3275);
DISPLAY 0.872340 (-2848 3275);
PAINT GREEN (-2848 3275);
DISPLAY INVISIBLE (-2848 3275);
FORCEPROP 1 LAST HDL_TAP TRUE
J 2
(-3175 3150);
DISPLAY 1.595745 (-3175 3150);
PAINT GREEN (-3175 3150);
DISPLAY INVISIBLE (-3175 3150);
FORCEPROP 1 LAST BODY_TYPE PLUMBING
J 2
(-2850 3225);
DISPLAY 1.595745 (-2850 3225);
PAINT GREEN (-2850 3225);
DISPLAY INVISIBLE (-2850 3225);
FORCEPROP 2 LAST CDS_LIB mstr_standard
J 0
(-2850 3275);
PAINT MONO (-2850 3275);
DISPLAY INVISIBLE (-2850 3275);
FORCEADD TAP..6
R 2
(-2850 3375);
FORCEPROP 3 LASTPIN (-2900 3375) SIG_NAME M_F_DQS_DN<10>
J 0
(-2890 3385);
DISPLAY 0.659574 (-2890 3385);
PAINT MONO (-2890 3385);
DISPLAY INVISIBLE (-2890 3385);
FORCEPROP 1 LASTPIN (-2900 3375) BN 10
J 2
(-2848 3383);
DISPLAY 0.617021 (-2848 3383);
PAINT PINK (-2848 3383);
FORCEPROP 1 LAST PATH I134
J 2
(-2848 3375);
DISPLAY 0.872340 (-2848 3375);
PAINT GREEN (-2848 3375);
DISPLAY INVISIBLE (-2848 3375);
FORCEPROP 1 LAST HDL_TAP TRUE
J 2
(-3175 3250);
DISPLAY 1.595745 (-3175 3250);
PAINT GREEN (-3175 3250);
DISPLAY INVISIBLE (-3175 3250);
FORCEPROP 1 LAST BODY_TYPE PLUMBING
J 2
(-2850 3325);
DISPLAY 1.595745 (-2850 3325);
PAINT GREEN (-2850 3325);
DISPLAY INVISIBLE (-2850 3325);
FORCEPROP 2 LAST CDS_LIB mstr_standard
J 0
(-2850 3375);
PAINT MONO (-2850 3375);
DISPLAY INVISIBLE (-2850 3375);
FORCEADD TAP..6
R 2
(-2850 3325);
FORCEPROP 3 LASTPIN (-2900 3325) SIG_NAME M_F_DQS_DN<9>
J 0
(-2890 3335);
DISPLAY 0.659574 (-2890 3335);
PAINT MONO (-2890 3335);
DISPLAY INVISIBLE (-2890 3335);
FORCEPROP 1 LASTPIN (-2900 3325) BN 9
J 2
(-2848 3333);
DISPLAY 0.617021 (-2848 3333);
PAINT PINK (-2848 3333);
FORCEPROP 1 LAST PATH I135
J 2
(-2848 3325);
DISPLAY 0.872340 (-2848 3325);
PAINT GREEN (-2848 3325);
DISPLAY INVISIBLE (-2848 3325);
FORCEPROP 1 LAST HDL_TAP TRUE
J 2
(-3175 3200);
DISPLAY 1.595745 (-3175 3200);
PAINT GREEN (-3175 3200);
DISPLAY INVISIBLE (-3175 3200);
FORCEPROP 1 LAST BODY_TYPE PLUMBING
J 2
(-2850 3275);
DISPLAY 1.595745 (-2850 3275);
PAINT GREEN (-2850 3275);
DISPLAY INVISIBLE (-2850 3275);
FORCEPROP 2 LAST CDS_LIB mstr_standard
J 0
(-2850 3325);
PAINT MONO (-2850 3325);
DISPLAY INVISIBLE (-2850 3325);
FORCEADD TAP..6
R 2
(-2850 3525);
FORCEPROP 3 LASTPIN (-2900 3525) SIG_NAME M_F_DQS_DN<13>
J 0
(-2890 3535);
DISPLAY 0.659574 (-2890 3535);
PAINT MONO (-2890 3535);
DISPLAY INVISIBLE (-2890 3535);
FORCEPROP 1 LASTPIN (-2900 3525) BN 13
J 2
(-2848 3533);
DISPLAY 0.617021 (-2848 3533);
PAINT PINK (-2848 3533);
FORCEPROP 1 LAST PATH I136
J 2
(-2848 3525);
DISPLAY 0.872340 (-2848 3525);
PAINT GREEN (-2848 3525);
DISPLAY INVISIBLE (-2848 3525);
FORCEPROP 1 LAST HDL_TAP TRUE
J 2
(-3175 3400);
DISPLAY 1.595745 (-3175 3400);
PAINT GREEN (-3175 3400);
DISPLAY INVISIBLE (-3175 3400);
FORCEPROP 1 LAST BODY_TYPE PLUMBING
J 2
(-2850 3475);
DISPLAY 1.595745 (-2850 3475);
PAINT GREEN (-2850 3475);
DISPLAY INVISIBLE (-2850 3475);
FORCEPROP 2 LAST CDS_LIB mstr_standard
J 0
(-2850 3525);
PAINT MONO (-2850 3525);
DISPLAY INVISIBLE (-2850 3525);
FORCEADD TAP..6
R 2
(-2850 3425);
FORCEPROP 3 LASTPIN (-2900 3425) SIG_NAME M_F_DQS_DN<11>
J 0
(-2890 3435);
DISPLAY 0.659574 (-2890 3435);
PAINT MONO (-2890 3435);
DISPLAY INVISIBLE (-2890 3435);
FORCEPROP 1 LASTPIN (-2900 3425) BN 11
J 2
(-2848 3433);
DISPLAY 0.617021 (-2848 3433);
PAINT PINK (-2848 3433);
FORCEPROP 1 LAST PATH I137
J 2
(-2848 3425);
DISPLAY 0.872340 (-2848 3425);
PAINT GREEN (-2848 3425);
DISPLAY INVISIBLE (-2848 3425);
FORCEPROP 1 LAST HDL_TAP TRUE
J 2
(-3175 3300);
DISPLAY 1.595745 (-3175 3300);
PAINT GREEN (-3175 3300);
DISPLAY INVISIBLE (-3175 3300);
FORCEPROP 1 LAST BODY_TYPE PLUMBING
J 2
(-2850 3375);
DISPLAY 1.595745 (-2850 3375);
PAINT GREEN (-2850 3375);
DISPLAY INVISIBLE (-2850 3375);
FORCEPROP 2 LAST CDS_LIB mstr_standard
J 0
(-2850 3425);
PAINT MONO (-2850 3425);
DISPLAY INVISIBLE (-2850 3425);
FORCEADD TAP..6
R 2
(-2850 3475);
FORCEPROP 3 LASTPIN (-2900 3475) SIG_NAME M_F_DQS_DN<12>
J 0
(-2890 3485);
DISPLAY 0.659574 (-2890 3485);
PAINT MONO (-2890 3485);
DISPLAY INVISIBLE (-2890 3485);
FORCEPROP 1 LASTPIN (-2900 3475) BN 12
J 2
(-2848 3483);
DISPLAY 0.617021 (-2848 3483);
PAINT PINK (-2848 3483);
FORCEPROP 1 LAST PATH I138
J 2
(-2848 3475);
DISPLAY 0.872340 (-2848 3475);
PAINT GREEN (-2848 3475);
DISPLAY INVISIBLE (-2848 3475);
FORCEPROP 1 LAST HDL_TAP TRUE
J 2
(-3175 3350);
DISPLAY 1.595745 (-3175 3350);
PAINT GREEN (-3175 3350);
DISPLAY INVISIBLE (-3175 3350);
FORCEPROP 1 LAST BODY_TYPE PLUMBING
J 2
(-2850 3425);
DISPLAY 1.595745 (-2850 3425);
PAINT GREEN (-2850 3425);
DISPLAY INVISIBLE (-2850 3425);
FORCEPROP 2 LAST CDS_LIB mstr_standard
J 0
(-2850 3475);
PAINT MONO (-2850 3475);
DISPLAY INVISIBLE (-2850 3475);
FORCEADD TAP..6
R 2
(-2850 3625);
FORCEPROP 3 LASTPIN (-2900 3625) SIG_NAME M_F_DQS_DN<15>
J 0
(-2890 3635);
DISPLAY 0.659574 (-2890 3635);
PAINT MONO (-2890 3635);
DISPLAY INVISIBLE (-2890 3635);
FORCEPROP 1 LASTPIN (-2900 3625) BN 15
J 2
(-2848 3633);
DISPLAY 0.617021 (-2848 3633);
PAINT PINK (-2848 3633);
FORCEPROP 1 LAST PATH I139
J 2
(-2848 3625);
DISPLAY 0.872340 (-2848 3625);
PAINT GREEN (-2848 3625);
DISPLAY INVISIBLE (-2848 3625);
FORCEPROP 1 LAST HDL_TAP TRUE
J 2
(-3175 3500);
DISPLAY 1.595745 (-3175 3500);
PAINT GREEN (-3175 3500);
DISPLAY INVISIBLE (-3175 3500);
FORCEPROP 1 LAST BODY_TYPE PLUMBING
J 2
(-2850 3575);
DISPLAY 1.595745 (-2850 3575);
PAINT GREEN (-2850 3575);
DISPLAY INVISIBLE (-2850 3575);
FORCEPROP 2 LAST CDS_LIB mstr_standard
J 0
(-2850 3625);
PAINT MONO (-2850 3625);
DISPLAY INVISIBLE (-2850 3625);
FORCEADD TAP..6
(-5575 1125);
FORCEPROP 3 LASTPIN (-5525 1125) SIG_NAME M_F_ECC<1>
J 0
(-5515 1135);
DISPLAY 0.659574 (-5515 1135);
PAINT MONO (-5515 1135);
DISPLAY INVISIBLE (-5515 1135);
FORCEPROP 1 LASTPIN (-5525 1125) BN 1
J 0
(-5577 1133);
DISPLAY 0.617021 (-5577 1133);
PAINT PINK (-5577 1133);
FORCEPROP 1 LAST PATH I14
J 0
(-5577 1125);
DISPLAY 0.872340 (-5577 1125);
PAINT GREEN (-5577 1125);
DISPLAY INVISIBLE (-5577 1125);
FORCEPROP 1 LAST HDL_TAP TRUE
J 0
(-5250 1000);
DISPLAY 1.595745 (-5250 1000);
PAINT GREEN (-5250 1000);
DISPLAY INVISIBLE (-5250 1000);
FORCEPROP 1 LAST BODY_TYPE PLUMBING
J 0
(-5575 1075);
DISPLAY 1.595745 (-5575 1075);
PAINT GREEN (-5575 1075);
DISPLAY INVISIBLE (-5575 1075);
FORCEPROP 2 LAST CDS_LIB mstr_standard
J 0
(-5575 1125);
PAINT MONO (-5575 1125);
DISPLAY INVISIBLE (-5575 1125);
FORCEADD TAP..6
R 2
(-2850 3575);
FORCEPROP 3 LASTPIN (-2900 3575) SIG_NAME M_F_DQS_DN<14>
J 0
(-2890 3585);
DISPLAY 0.659574 (-2890 3585);
PAINT MONO (-2890 3585);
DISPLAY INVISIBLE (-2890 3585);
FORCEPROP 1 LASTPIN (-2900 3575) BN 14
J 2
(-2848 3583);
DISPLAY 0.617021 (-2848 3583);
PAINT PINK (-2848 3583);
FORCEPROP 1 LAST PATH I140
J 2
(-2848 3575);
DISPLAY 0.872340 (-2848 3575);
PAINT GREEN (-2848 3575);
DISPLAY INVISIBLE (-2848 3575);
FORCEPROP 1 LAST HDL_TAP TRUE
J 2
(-3175 3450);
DISPLAY 1.595745 (-3175 3450);
PAINT GREEN (-3175 3450);
DISPLAY INVISIBLE (-3175 3450);
FORCEPROP 1 LAST BODY_TYPE PLUMBING
J 2
(-2850 3525);
DISPLAY 1.595745 (-2850 3525);
PAINT GREEN (-2850 3525);
DISPLAY INVISIBLE (-2850 3525);
FORCEPROP 2 LAST CDS_LIB mstr_standard
J 0
(-2850 3575);
PAINT MONO (-2850 3575);
DISPLAY INVISIBLE (-2850 3575);
FORCEADD TAP..6
R 2
(-2850 3725);
FORCEPROP 3 LASTPIN (-2900 3725) SIG_NAME M_F_DQS_DN<17>
J 0
(-2890 3735);
DISPLAY 0.659574 (-2890 3735);
PAINT MONO (-2890 3735);
DISPLAY INVISIBLE (-2890 3735);
FORCEPROP 1 LASTPIN (-2900 3725) BN 17
J 2
(-2848 3733);
DISPLAY 0.617021 (-2848 3733);
PAINT PINK (-2848 3733);
FORCEPROP 1 LAST PATH I141
J 2
(-2848 3725);
DISPLAY 0.872340 (-2848 3725);
PAINT GREEN (-2848 3725);
DISPLAY INVISIBLE (-2848 3725);
FORCEPROP 1 LAST HDL_TAP TRUE
J 2
(-3175 3600);
DISPLAY 1.595745 (-3175 3600);
PAINT GREEN (-3175 3600);
DISPLAY INVISIBLE (-3175 3600);
FORCEPROP 1 LAST BODY_TYPE PLUMBING
J 2
(-2850 3675);
DISPLAY 1.595745 (-2850 3675);
PAINT GREEN (-2850 3675);
DISPLAY INVISIBLE (-2850 3675);
FORCEPROP 2 LAST CDS_LIB mstr_standard
J 0
(-2850 3725);
PAINT MONO (-2850 3725);
DISPLAY INVISIBLE (-2850 3725);
FORCEADD TAP..6
R 2
(-2850 3675);
FORCEPROP 3 LASTPIN (-2900 3675) SIG_NAME M_F_DQS_DN<16>
J 0
(-2890 3685);
DISPLAY 0.659574 (-2890 3685);
PAINT MONO (-2890 3685);
DISPLAY INVISIBLE (-2890 3685);
FORCEPROP 1 LASTPIN (-2900 3675) BN 16
J 2
(-2848 3683);
DISPLAY 0.617021 (-2848 3683);
PAINT PINK (-2848 3683);
FORCEPROP 1 LAST PATH I142
J 2
(-2848 3675);
DISPLAY 0.872340 (-2848 3675);
PAINT GREEN (-2848 3675);
DISPLAY INVISIBLE (-2848 3675);
FORCEPROP 1 LAST HDL_TAP TRUE
J 2
(-3175 3550);
DISPLAY 1.595745 (-3175 3550);
PAINT GREEN (-3175 3550);
DISPLAY INVISIBLE (-3175 3550);
FORCEPROP 1 LAST BODY_TYPE PLUMBING
J 2
(-2850 3625);
DISPLAY 1.595745 (-2850 3625);
PAINT GREEN (-2850 3625);
DISPLAY INVISIBLE (-2850 3625);
FORCEPROP 2 LAST CDS_LIB mstr_standard
J 0
(-2850 3675);
PAINT MONO (-2850 3675);
DISPLAY INVISIBLE (-2850 3675);
FORCEADD TAP..6
R 2
(-2850 3875);
FORCEPROP 3 LASTPIN (-2900 3875) SIG_NAME M_F_DQS_DP<1>
J 0
(-2890 3885);
DISPLAY 0.659574 (-2890 3885);
PAINT MONO (-2890 3885);
DISPLAY INVISIBLE (-2890 3885);
FORCEPROP 1 LASTPIN (-2900 3875) BN 1
J 2
(-2848 3883);
DISPLAY 0.617021 (-2848 3883);
PAINT PINK (-2848 3883);
FORCEPROP 1 LAST PATH I143
J 2
(-2848 3875);
DISPLAY 0.872340 (-2848 3875);
PAINT GREEN (-2848 3875);
DISPLAY INVISIBLE (-2848 3875);
FORCEPROP 1 LAST HDL_TAP TRUE
J 2
(-3175 3750);
DISPLAY 1.595745 (-3175 3750);
PAINT GREEN (-3175 3750);
DISPLAY INVISIBLE (-3175 3750);
FORCEPROP 1 LAST BODY_TYPE PLUMBING
J 2
(-2850 3825);
DISPLAY 1.595745 (-2850 3825);
PAINT GREEN (-2850 3825);
DISPLAY INVISIBLE (-2850 3825);
FORCEPROP 2 LAST CDS_LIB mstr_standard
J 0
(-2850 3875);
PAINT MONO (-2850 3875);
DISPLAY INVISIBLE (-2850 3875);
FORCEADD TAP..6
R 2
(-2850 3825);
FORCEPROP 3 LASTPIN (-2900 3825) SIG_NAME M_F_DQS_DP<0>
J 0
(-2890 3835);
DISPLAY 0.659574 (-2890 3835);
PAINT MONO (-2890 3835);
DISPLAY INVISIBLE (-2890 3835);
FORCEPROP 1 LASTPIN (-2900 3825) BN 0
J 2
(-2848 3833);
DISPLAY 0.617021 (-2848 3833);
PAINT PINK (-2848 3833);
FORCEPROP 1 LAST PATH I144
J 2
(-2848 3825);
DISPLAY 0.872340 (-2848 3825);
PAINT GREEN (-2848 3825);
DISPLAY INVISIBLE (-2848 3825);
FORCEPROP 1 LAST HDL_TAP TRUE
J 2
(-3175 3700);
DISPLAY 1.595745 (-3175 3700);
PAINT GREEN (-3175 3700);
DISPLAY INVISIBLE (-3175 3700);
FORCEPROP 1 LAST BODY_TYPE PLUMBING
J 2
(-2850 3775);
DISPLAY 1.595745 (-2850 3775);
PAINT GREEN (-2850 3775);
DISPLAY INVISIBLE (-2850 3775);
FORCEPROP 2 LAST CDS_LIB mstr_standard
J 0
(-2850 3825);
PAINT MONO (-2850 3825);
DISPLAY INVISIBLE (-2850 3825);
FORCEADD TAP..6
R 2
(-2850 4025);
FORCEPROP 3 LASTPIN (-2900 4025) SIG_NAME M_F_DQS_DP<4>
J 0
(-2890 4035);
DISPLAY 0.659574 (-2890 4035);
PAINT MONO (-2890 4035);
DISPLAY INVISIBLE (-2890 4035);
FORCEPROP 1 LASTPIN (-2900 4025) BN 4
J 2
(-2848 4033);
DISPLAY 0.617021 (-2848 4033);
PAINT PINK (-2848 4033);
FORCEPROP 1 LAST PATH I145
J 2
(-2848 4025);
DISPLAY 0.872340 (-2848 4025);
PAINT GREEN (-2848 4025);
DISPLAY INVISIBLE (-2848 4025);
FORCEPROP 1 LAST HDL_TAP TRUE
J 2
(-3175 3900);
DISPLAY 1.595745 (-3175 3900);
PAINT GREEN (-3175 3900);
DISPLAY INVISIBLE (-3175 3900);
FORCEPROP 1 LAST BODY_TYPE PLUMBING
J 2
(-2850 3975);
DISPLAY 1.595745 (-2850 3975);
PAINT GREEN (-2850 3975);
DISPLAY INVISIBLE (-2850 3975);
FORCEPROP 2 LAST CDS_LIB mstr_standard
J 0
(-2850 4025);
PAINT MONO (-2850 4025);
DISPLAY INVISIBLE (-2850 4025);
FORCEADD TAP..6
R 2
(-2850 3975);
FORCEPROP 3 LASTPIN (-2900 3975) SIG_NAME M_F_DQS_DP<3>
J 0
(-2890 3985);
DISPLAY 0.659574 (-2890 3985);
PAINT MONO (-2890 3985);
DISPLAY INVISIBLE (-2890 3985);
FORCEPROP 1 LASTPIN (-2900 3975) BN 3
J 2
(-2848 3983);
DISPLAY 0.617021 (-2848 3983);
PAINT PINK (-2848 3983);
FORCEPROP 1 LAST PATH I146
J 2
(-2848 3975);
DISPLAY 0.872340 (-2848 3975);
PAINT GREEN (-2848 3975);
DISPLAY INVISIBLE (-2848 3975);
FORCEPROP 1 LAST HDL_TAP TRUE
J 2
(-3175 3850);
DISPLAY 1.595745 (-3175 3850);
PAINT GREEN (-3175 3850);
DISPLAY INVISIBLE (-3175 3850);
FORCEPROP 1 LAST BODY_TYPE PLUMBING
J 2
(-2850 3925);
DISPLAY 1.595745 (-2850 3925);
PAINT GREEN (-2850 3925);
DISPLAY INVISIBLE (-2850 3925);
FORCEPROP 2 LAST CDS_LIB mstr_standard
J 0
(-2850 3975);
PAINT MONO (-2850 3975);
DISPLAY INVISIBLE (-2850 3975);
FORCEADD TAP..6
R 2
(-2850 3925);
FORCEPROP 3 LASTPIN (-2900 3925) SIG_NAME M_F_DQS_DP<2>
J 0
(-2890 3935);
DISPLAY 0.659574 (-2890 3935);
PAINT MONO (-2890 3935);
DISPLAY INVISIBLE (-2890 3935);
FORCEPROP 1 LASTPIN (-2900 3925) BN 2
J 2
(-2848 3933);
DISPLAY 0.617021 (-2848 3933);
PAINT PINK (-2848 3933);
FORCEPROP 1 LAST PATH I147
J 2
(-2848 3925);
DISPLAY 0.872340 (-2848 3925);
PAINT GREEN (-2848 3925);
DISPLAY INVISIBLE (-2848 3925);
FORCEPROP 1 LAST HDL_TAP TRUE
J 2
(-3175 3800);
DISPLAY 1.595745 (-3175 3800);
PAINT GREEN (-3175 3800);
DISPLAY INVISIBLE (-3175 3800);
FORCEPROP 1 LAST BODY_TYPE PLUMBING
J 2
(-2850 3875);
DISPLAY 1.595745 (-2850 3875);
PAINT GREEN (-2850 3875);
DISPLAY INVISIBLE (-2850 3875);
FORCEPROP 2 LAST CDS_LIB mstr_standard
J 0
(-2850 3925);
PAINT MONO (-2850 3925);
DISPLAY INVISIBLE (-2850 3925);
FORCEADD OFFPAGE..4
(-2000 575);
FORCEPROP 2 LAST $XR1 54 
J 0
(-1724 575);
DISPLAY 0.638298 (-1724 575);
PAINT MONO (-1724 575);
FORCEPROP 2 LAST $XR0 53 
J 0
(-1814 575);
DISPLAY 0.638298 (-1814 575);
PAINT MONO (-1814 575);
FORCEPROP 2 LAST PATH I148
J 0
(-1825 650);
DISPLAY 1.021277 (-1825 650);
PAINT ORANGE (-1825 650);
DISPLAY INVISIBLE (-1825 650);
FORCEPROP 1 LAST COMMENT_BODY TRUE
J 0
(-2025 475);
DISPLAY 1.170213 (-2025 475);
PAINT GREEN (-2025 475);
DISPLAY INVISIBLE (-2025 475);
FORCEPROP 1 LAST OFFPAGE TRUE
J 0
(-1675 450);
DISPLAY 1.170213 (-1675 450);
PAINT GREEN (-1675 450);
DISPLAY INVISIBLE (-1675 450);
FORCEPROP 2 LAST CDS_LIB mstr_standard
J 0
(-2000 575);
PAINT MONO (-2000 575);
DISPLAY INVISIBLE (-2000 575);
FORCEADD OFFPAGE..2
(-2000 525);
FORCEPROP 2 LAST $XR1 54 
J 0
(-1721 525);
DISPLAY 0.638298 (-1721 525);
PAINT MONO (-1721 525);
FORCEPROP 2 LAST $XR0 53 
J 0
(-1811 525);
DISPLAY 0.638298 (-1811 525);
PAINT MONO (-1811 525);
FORCEPROP 2 LAST PATH I149
J 0
(-1825 600);
DISPLAY 1.021277 (-1825 600);
PAINT ORANGE (-1825 600);
DISPLAY INVISIBLE (-1825 600);
FORCEPROP 1 LAST COMMENT_BODY TRUE
J 0
(-2045 430);
DISPLAY 1.170213 (-2045 430);
PAINT GREEN (-2045 430);
DISPLAY INVISIBLE (-2045 430);
FORCEPROP 1 LAST OFFPAGE TRUE
J 0
(-1675 400);
DISPLAY 1.170213 (-1675 400);
PAINT GREEN (-1675 400);
DISPLAY INVISIBLE (-1675 400);
FORCEPROP 2 LAST CDS_LIB mstr_standard
J 0
(-2000 525);
PAINT MONO (-2000 525);
DISPLAY INVISIBLE (-2000 525);
FORCEADD TAP..6
(-5575 1175);
FORCEPROP 3 LASTPIN (-5525 1175) SIG_NAME M_F_ECC<2>
J 0
(-5515 1185);
DISPLAY 0.659574 (-5515 1185);
PAINT MONO (-5515 1185);
DISPLAY INVISIBLE (-5515 1185);
FORCEPROP 1 LASTPIN (-5525 1175) BN 2
J 0
(-5577 1183);
DISPLAY 0.617021 (-5577 1183);
PAINT PINK (-5577 1183);
FORCEPROP 1 LAST PATH I15
J 0
(-5577 1175);
DISPLAY 0.872340 (-5577 1175);
PAINT GREEN (-5577 1175);
DISPLAY INVISIBLE (-5577 1175);
FORCEPROP 1 LAST HDL_TAP TRUE
J 0
(-5250 1050);
DISPLAY 1.595745 (-5250 1050);
PAINT GREEN (-5250 1050);
DISPLAY INVISIBLE (-5250 1050);
FORCEPROP 1 LAST BODY_TYPE PLUMBING
J 0
(-5575 1125);
DISPLAY 1.595745 (-5575 1125);
PAINT GREEN (-5575 1125);
DISPLAY INVISIBLE (-5575 1125);
FORCEPROP 2 LAST CDS_LIB mstr_standard
J 0
(-5575 1175);
PAINT MONO (-5575 1175);
DISPLAY INVISIBLE (-5575 1175);
FORCEADD OFFPAGE..2
(-2000 625);
FORCEPROP 2 LAST $XR1 54 
J 0
(-1721 625);
DISPLAY 0.638298 (-1721 625);
PAINT MONO (-1721 625);
FORCEPROP 2 LAST $XR0 53 
J 0
(-1811 625);
DISPLAY 0.638298 (-1811 625);
PAINT MONO (-1811 625);
FORCEPROP 2 LAST PATH I150
J 0
(-1825 700);
DISPLAY 1.021277 (-1825 700);
PAINT ORANGE (-1825 700);
DISPLAY INVISIBLE (-1825 700);
FORCEPROP 1 LAST COMMENT_BODY TRUE
J 0
(-2045 530);
DISPLAY 1.170213 (-2045 530);
PAINT GREEN (-2045 530);
DISPLAY INVISIBLE (-2045 530);
FORCEPROP 1 LAST OFFPAGE TRUE
J 0
(-1675 500);
DISPLAY 1.170213 (-1675 500);
PAINT GREEN (-1675 500);
DISPLAY INVISIBLE (-1675 500);
FORCEPROP 2 LAST CDS_LIB mstr_standard
J 0
(-2000 625);
PAINT MONO (-2000 625);
DISPLAY INVISIBLE (-2000 625);
FORCEADD OFFPAGE..2
(-2000 825);
FORCEPROP 2 LAST $XR1 54 
J 0
(-1721 825);
DISPLAY 0.638298 (-1721 825);
PAINT MONO (-1721 825);
FORCEPROP 2 LAST $XR0 53 
J 0
(-1811 825);
DISPLAY 0.638298 (-1811 825);
PAINT MONO (-1811 825);
FORCEPROP 2 LAST PATH I151
J 0
(-1825 900);
DISPLAY 1.021277 (-1825 900);
PAINT ORANGE (-1825 900);
DISPLAY INVISIBLE (-1825 900);
FORCEPROP 1 LAST COMMENT_BODY TRUE
J 0
(-2045 730);
DISPLAY 1.170213 (-2045 730);
PAINT GREEN (-2045 730);
DISPLAY INVISIBLE (-2045 730);
FORCEPROP 1 LAST OFFPAGE TRUE
J 0
(-1675 700);
DISPLAY 1.170213 (-1675 700);
PAINT GREEN (-1675 700);
DISPLAY INVISIBLE (-1675 700);
FORCEPROP 2 LAST CDS_LIB mstr_standard
J 0
(-2000 825);
PAINT MONO (-2000 825);
DISPLAY INVISIBLE (-2000 825);
FORCEADD OFFPAGE..2
(-2000 925);
FORCEPROP 2 LAST $XR1 54 
J 0
(-1721 925);
DISPLAY 0.638298 (-1721 925);
PAINT MONO (-1721 925);
FORCEPROP 2 LAST $XR0 53 
J 0
(-1811 925);
DISPLAY 0.638298 (-1811 925);
PAINT MONO (-1811 925);
FORCEPROP 2 LAST PATH I152
J 0
(-1825 1000);
DISPLAY 1.021277 (-1825 1000);
PAINT ORANGE (-1825 1000);
DISPLAY INVISIBLE (-1825 1000);
FORCEPROP 1 LAST COMMENT_BODY TRUE
J 0
(-2045 830);
DISPLAY 1.170213 (-2045 830);
PAINT GREEN (-2045 830);
DISPLAY INVISIBLE (-2045 830);
FORCEPROP 1 LAST OFFPAGE TRUE
J 0
(-1675 800);
DISPLAY 1.170213 (-1675 800);
PAINT GREEN (-1675 800);
DISPLAY INVISIBLE (-1675 800);
FORCEPROP 2 LAST CDS_LIB mstr_standard
J 0
(-2000 925);
PAINT MONO (-2000 925);
DISPLAY INVISIBLE (-2000 925);
FORCEADD OFFPAGE..2
(-2000 1375);
FORCEPROP 2 LAST $XR1 54 
J 0
(-1721 1375);
DISPLAY 0.638298 (-1721 1375);
PAINT MONO (-1721 1375);
FORCEPROP 2 LAST $XR0 53 
J 0
(-1811 1375);
DISPLAY 0.638298 (-1811 1375);
PAINT MONO (-1811 1375);
FORCEPROP 2 LAST PATH I153
J 0
(-1825 1450);
DISPLAY 1.021277 (-1825 1450);
PAINT ORANGE (-1825 1450);
DISPLAY INVISIBLE (-1825 1450);
FORCEPROP 1 LAST COMMENT_BODY TRUE
J 0
(-2045 1280);
DISPLAY 1.170213 (-2045 1280);
PAINT GREEN (-2045 1280);
DISPLAY INVISIBLE (-2045 1280);
FORCEPROP 1 LAST OFFPAGE TRUE
J 0
(-1675 1250);
DISPLAY 1.170213 (-1675 1250);
PAINT GREEN (-1675 1250);
DISPLAY INVISIBLE (-1675 1250);
FORCEPROP 2 LAST CDS_LIB mstr_standard
J 0
(-2000 1375);
PAINT MONO (-2000 1375);
DISPLAY INVISIBLE (-2000 1375);
FORCEADD OFFPAGE..2
(-2000 1625);
FORCEPROP 2 LAST $XR1 54 
J 0
(-1721 1625);
DISPLAY 0.638298 (-1721 1625);
PAINT MONO (-1721 1625);
FORCEPROP 2 LAST $XR0 53 
J 0
(-1811 1625);
DISPLAY 0.638298 (-1811 1625);
PAINT MONO (-1811 1625);
FORCEPROP 2 LAST PATH I154
J 0
(-1825 1700);
DISPLAY 1.021277 (-1825 1700);
PAINT ORANGE (-1825 1700);
DISPLAY INVISIBLE (-1825 1700);
FORCEPROP 1 LAST COMMENT_BODY TRUE
J 0
(-2045 1530);
DISPLAY 1.170213 (-2045 1530);
PAINT GREEN (-2045 1530);
DISPLAY INVISIBLE (-2045 1530);
FORCEPROP 1 LAST OFFPAGE TRUE
J 0
(-1675 1500);
DISPLAY 1.170213 (-1675 1500);
PAINT GREEN (-1675 1500);
DISPLAY INVISIBLE (-1675 1500);
FORCEPROP 2 LAST CDS_LIB mstr_standard
J 0
(-2000 1625);
PAINT MONO (-2000 1625);
DISPLAY INVISIBLE (-2000 1625);
FORCEADD OFFPAGE..2
(-2000 1875);
FORCEPROP 2 LAST $XR1 54 
J 0
(-1721 1875);
DISPLAY 0.638298 (-1721 1875);
PAINT MONO (-1721 1875);
FORCEPROP 2 LAST $XR0 53 
J 0
(-1811 1875);
DISPLAY 0.638298 (-1811 1875);
PAINT MONO (-1811 1875);
FORCEPROP 2 LAST PATH I155
J 0
(-1825 1950);
DISPLAY 1.021277 (-1825 1950);
PAINT ORANGE (-1825 1950);
DISPLAY INVISIBLE (-1825 1950);
FORCEPROP 1 LAST COMMENT_BODY TRUE
J 0
(-2045 1780);
DISPLAY 1.170213 (-2045 1780);
PAINT GREEN (-2045 1780);
DISPLAY INVISIBLE (-2045 1780);
FORCEPROP 1 LAST OFFPAGE TRUE
J 0
(-1675 1750);
DISPLAY 1.170213 (-1675 1750);
PAINT GREEN (-1675 1750);
DISPLAY INVISIBLE (-1675 1750);
FORCEPROP 2 LAST CDS_LIB mstr_standard
J 0
(-2000 1875);
PAINT MONO (-2000 1875);
DISPLAY INVISIBLE (-2000 1875);
FORCEADD OFFPAGE..2
(-2000 2825);
FORCEPROP 2 LAST $XR1 54 
J 0
(-1721 2825);
DISPLAY 0.638298 (-1721 2825);
PAINT MONO (-1721 2825);
FORCEPROP 2 LAST $XR0 53 
J 0
(-1811 2825);
DISPLAY 0.638298 (-1811 2825);
PAINT MONO (-1811 2825);
FORCEPROP 2 LAST PATH I156
J 0
(-1825 2900);
DISPLAY 1.021277 (-1825 2900);
PAINT ORANGE (-1825 2900);
DISPLAY INVISIBLE (-1825 2900);
FORCEPROP 1 LAST COMMENT_BODY TRUE
J 0
(-2045 2730);
DISPLAY 1.170213 (-2045 2730);
PAINT GREEN (-2045 2730);
DISPLAY INVISIBLE (-2045 2730);
FORCEPROP 1 LAST OFFPAGE TRUE
J 0
(-1675 2700);
DISPLAY 1.170213 (-1675 2700);
PAINT GREEN (-1675 2700);
DISPLAY INVISIBLE (-1675 2700);
FORCEPROP 2 LAST CDS_LIB mstr_standard
J 0
(-2000 2825);
PAINT MONO (-2000 2825);
DISPLAY INVISIBLE (-2000 2825);
FORCEADD OFFPAGE..3
(-2000 3775);
FORCEPROP 2 LAST $XR1 54 
J 0
(-1696 3775);
DISPLAY 0.638298 (-1696 3775);
PAINT MONO (-1696 3775);
FORCEPROP 2 LAST $XR0 53 
J 0
(-1786 3775);
DISPLAY 0.638298 (-1786 3775);
PAINT MONO (-1786 3775);
FORCEPROP 2 LAST PATH I157
J 0
(-1800 3850);
DISPLAY 1.021277 (-1800 3850);
PAINT ORANGE (-1800 3850);
DISPLAY INVISIBLE (-1800 3850);
FORCEPROP 1 LAST COMMENT_BODY TRUE
J 0
(-2050 3675);
DISPLAY 1.170213 (-2050 3675);
PAINT GREEN (-2050 3675);
DISPLAY INVISIBLE (-2050 3675);
FORCEPROP 1 LAST OFFPAGE TRUE
J 0
(-1675 3650);
DISPLAY 1.170213 (-1675 3650);
PAINT GREEN (-1675 3650);
DISPLAY INVISIBLE (-1675 3650);
FORCEPROP 2 LAST CDS_LIB mstr_standard
J 0
(-2000 3775);
PAINT MONO (-2000 3775);
DISPLAY INVISIBLE (-2000 3775);
FORCEADD TAP..6
R 2
(-2850 4125);
FORCEPROP 3 LASTPIN (-2900 4125) SIG_NAME M_F_DQS_DP<6>
J 0
(-2890 4135);
DISPLAY 0.659574 (-2890 4135);
PAINT MONO (-2890 4135);
DISPLAY INVISIBLE (-2890 4135);
FORCEPROP 1 LASTPIN (-2900 4125) BN 6
J 2
(-2848 4133);
DISPLAY 0.617021 (-2848 4133);
PAINT PINK (-2848 4133);
FORCEPROP 1 LAST PATH I158
J 2
(-2848 4125);
DISPLAY 0.872340 (-2848 4125);
PAINT GREEN (-2848 4125);
DISPLAY INVISIBLE (-2848 4125);
FORCEPROP 1 LAST HDL_TAP TRUE
J 2
(-3175 4000);
DISPLAY 1.595745 (-3175 4000);
PAINT GREEN (-3175 4000);
DISPLAY INVISIBLE (-3175 4000);
FORCEPROP 1 LAST BODY_TYPE PLUMBING
J 2
(-2850 4075);
DISPLAY 1.595745 (-2850 4075);
PAINT GREEN (-2850 4075);
DISPLAY INVISIBLE (-2850 4075);
FORCEPROP 2 LAST CDS_LIB mstr_standard
J 0
(-2850 4125);
PAINT MONO (-2850 4125);
DISPLAY INVISIBLE (-2850 4125);
FORCEADD TAP..6
R 2
(-2850 4075);
FORCEPROP 3 LASTPIN (-2900 4075) SIG_NAME M_F_DQS_DP<5>
J 0
(-2890 4085);
DISPLAY 0.659574 (-2890 4085);
PAINT MONO (-2890 4085);
DISPLAY INVISIBLE (-2890 4085);
FORCEPROP 1 LASTPIN (-2900 4075) BN 5
J 2
(-2848 4083);
DISPLAY 0.617021 (-2848 4083);
PAINT PINK (-2848 4083);
FORCEPROP 1 LAST PATH I159
J 2
(-2848 4075);
DISPLAY 0.872340 (-2848 4075);
PAINT GREEN (-2848 4075);
DISPLAY INVISIBLE (-2848 4075);
FORCEPROP 1 LAST HDL_TAP TRUE
J 2
(-3175 3950);
DISPLAY 1.595745 (-3175 3950);
PAINT GREEN (-3175 3950);
DISPLAY INVISIBLE (-3175 3950);
FORCEPROP 1 LAST BODY_TYPE PLUMBING
J 2
(-2850 4025);
DISPLAY 1.595745 (-2850 4025);
PAINT GREEN (-2850 4025);
DISPLAY INVISIBLE (-2850 4025);
FORCEPROP 2 LAST CDS_LIB mstr_standard
J 0
(-2850 4075);
PAINT MONO (-2850 4075);
DISPLAY INVISIBLE (-2850 4075);
FORCEADD TAP..6
(-5575 1225);
FORCEPROP 3 LASTPIN (-5525 1225) SIG_NAME M_F_ECC<3>
J 0
(-5515 1235);
DISPLAY 0.659574 (-5515 1235);
PAINT MONO (-5515 1235);
DISPLAY INVISIBLE (-5515 1235);
FORCEPROP 1 LASTPIN (-5525 1225) BN 3
J 0
(-5577 1233);
DISPLAY 0.617021 (-5577 1233);
PAINT PINK (-5577 1233);
FORCEPROP 1 LAST PATH I16
J 0
(-5577 1225);
DISPLAY 0.872340 (-5577 1225);
PAINT GREEN (-5577 1225);
DISPLAY INVISIBLE (-5577 1225);
FORCEPROP 1 LAST HDL_TAP TRUE
J 0
(-5250 1100);
DISPLAY 1.595745 (-5250 1100);
PAINT GREEN (-5250 1100);
DISPLAY INVISIBLE (-5250 1100);
FORCEPROP 1 LAST BODY_TYPE PLUMBING
J 0
(-5575 1175);
DISPLAY 1.595745 (-5575 1175);
PAINT GREEN (-5575 1175);
DISPLAY INVISIBLE (-5575 1175);
FORCEPROP 2 LAST CDS_LIB mstr_standard
J 0
(-5575 1225);
PAINT MONO (-5575 1225);
DISPLAY INVISIBLE (-5575 1225);
FORCEADD TAP..6
R 2
(-2850 4175);
FORCEPROP 3 LASTPIN (-2900 4175) SIG_NAME M_F_DQS_DP<7>
J 0
(-2890 4185);
DISPLAY 0.659574 (-2890 4185);
PAINT MONO (-2890 4185);
DISPLAY INVISIBLE (-2890 4185);
FORCEPROP 1 LASTPIN (-2900 4175) BN 7
J 2
(-2848 4183);
DISPLAY 0.617021 (-2848 4183);
PAINT PINK (-2848 4183);
FORCEPROP 1 LAST PATH I160
J 2
(-2848 4175);
DISPLAY 0.872340 (-2848 4175);
PAINT GREEN (-2848 4175);
DISPLAY INVISIBLE (-2848 4175);
FORCEPROP 1 LAST HDL_TAP TRUE
J 2
(-3175 4050);
DISPLAY 1.595745 (-3175 4050);
PAINT GREEN (-3175 4050);
DISPLAY INVISIBLE (-3175 4050);
FORCEPROP 1 LAST BODY_TYPE PLUMBING
J 2
(-2850 4125);
DISPLAY 1.595745 (-2850 4125);
PAINT GREEN (-2850 4125);
DISPLAY INVISIBLE (-2850 4125);
FORCEPROP 2 LAST CDS_LIB mstr_standard
J 0
(-2850 4175);
PAINT MONO (-2850 4175);
DISPLAY INVISIBLE (-2850 4175);
FORCEADD TAP..6
R 2
(-2850 4275);
FORCEPROP 3 LASTPIN (-2900 4275) SIG_NAME M_F_DQS_DP<9>
J 0
(-2890 4285);
DISPLAY 0.659574 (-2890 4285);
PAINT MONO (-2890 4285);
DISPLAY INVISIBLE (-2890 4285);
FORCEPROP 1 LASTPIN (-2900 4275) BN 9
J 2
(-2848 4283);
DISPLAY 0.617021 (-2848 4283);
PAINT PINK (-2848 4283);
FORCEPROP 1 LAST PATH I161
J 2
(-2848 4275);
DISPLAY 0.872340 (-2848 4275);
PAINT GREEN (-2848 4275);
DISPLAY INVISIBLE (-2848 4275);
FORCEPROP 1 LAST HDL_TAP TRUE
J 2
(-3175 4150);
DISPLAY 1.595745 (-3175 4150);
PAINT GREEN (-3175 4150);
DISPLAY INVISIBLE (-3175 4150);
FORCEPROP 1 LAST BODY_TYPE PLUMBING
J 2
(-2850 4225);
DISPLAY 1.595745 (-2850 4225);
PAINT GREEN (-2850 4225);
DISPLAY INVISIBLE (-2850 4225);
FORCEPROP 2 LAST CDS_LIB mstr_standard
J 0
(-2850 4275);
PAINT MONO (-2850 4275);
DISPLAY INVISIBLE (-2850 4275);
FORCEADD TAP..6
R 2
(-2850 4225);
FORCEPROP 3 LASTPIN (-2900 4225) SIG_NAME M_F_DQS_DP<8>
J 0
(-2890 4235);
DISPLAY 0.659574 (-2890 4235);
PAINT MONO (-2890 4235);
DISPLAY INVISIBLE (-2890 4235);
FORCEPROP 1 LASTPIN (-2900 4225) BN 8
J 2
(-2848 4233);
DISPLAY 0.617021 (-2848 4233);
PAINT PINK (-2848 4233);
FORCEPROP 1 LAST PATH I162
J 2
(-2848 4225);
DISPLAY 0.872340 (-2848 4225);
PAINT GREEN (-2848 4225);
DISPLAY INVISIBLE (-2848 4225);
FORCEPROP 1 LAST HDL_TAP TRUE
J 2
(-3175 4100);
DISPLAY 1.595745 (-3175 4100);
PAINT GREEN (-3175 4100);
DISPLAY INVISIBLE (-3175 4100);
FORCEPROP 1 LAST BODY_TYPE PLUMBING
J 2
(-2850 4175);
DISPLAY 1.595745 (-2850 4175);
PAINT GREEN (-2850 4175);
DISPLAY INVISIBLE (-2850 4175);
FORCEPROP 2 LAST CDS_LIB mstr_standard
J 0
(-2850 4225);
PAINT MONO (-2850 4225);
DISPLAY INVISIBLE (-2850 4225);
FORCEADD TAP..6
R 2
(-2850 4425);
FORCEPROP 3 LASTPIN (-2900 4425) SIG_NAME M_F_DQS_DP<12>
J 0
(-2890 4435);
DISPLAY 0.659574 (-2890 4435);
PAINT MONO (-2890 4435);
DISPLAY INVISIBLE (-2890 4435);
FORCEPROP 1 LASTPIN (-2900 4425) BN 12
J 2
(-2848 4433);
DISPLAY 0.617021 (-2848 4433);
PAINT PINK (-2848 4433);
FORCEPROP 1 LAST PATH I163
J 2
(-2848 4425);
DISPLAY 0.872340 (-2848 4425);
PAINT GREEN (-2848 4425);
DISPLAY INVISIBLE (-2848 4425);
FORCEPROP 1 LAST HDL_TAP TRUE
J 2
(-3175 4300);
DISPLAY 1.595745 (-3175 4300);
PAINT GREEN (-3175 4300);
DISPLAY INVISIBLE (-3175 4300);
FORCEPROP 1 LAST BODY_TYPE PLUMBING
J 2
(-2850 4375);
DISPLAY 1.595745 (-2850 4375);
PAINT GREEN (-2850 4375);
DISPLAY INVISIBLE (-2850 4375);
FORCEPROP 2 LAST CDS_LIB mstr_standard
J 0
(-2850 4425);
PAINT MONO (-2850 4425);
DISPLAY INVISIBLE (-2850 4425);
FORCEADD TAP..6
R 2
(-2850 4375);
FORCEPROP 3 LASTPIN (-2900 4375) SIG_NAME M_F_DQS_DP<11>
J 0
(-2890 4385);
DISPLAY 0.659574 (-2890 4385);
PAINT MONO (-2890 4385);
DISPLAY INVISIBLE (-2890 4385);
FORCEPROP 1 LASTPIN (-2900 4375) BN 11
J 2
(-2848 4383);
DISPLAY 0.617021 (-2848 4383);
PAINT PINK (-2848 4383);
FORCEPROP 1 LAST PATH I164
J 2
(-2848 4375);
DISPLAY 0.872340 (-2848 4375);
PAINT GREEN (-2848 4375);
DISPLAY INVISIBLE (-2848 4375);
FORCEPROP 1 LAST HDL_TAP TRUE
J 2
(-3175 4250);
DISPLAY 1.595745 (-3175 4250);
PAINT GREEN (-3175 4250);
DISPLAY INVISIBLE (-3175 4250);
FORCEPROP 1 LAST BODY_TYPE PLUMBING
J 2
(-2850 4325);
DISPLAY 1.595745 (-2850 4325);
PAINT GREEN (-2850 4325);
DISPLAY INVISIBLE (-2850 4325);
FORCEPROP 2 LAST CDS_LIB mstr_standard
J 0
(-2850 4375);
PAINT MONO (-2850 4375);
DISPLAY INVISIBLE (-2850 4375);
FORCEADD TAP..6
R 2
(-2850 4325);
FORCEPROP 3 LASTPIN (-2900 4325) SIG_NAME M_F_DQS_DP<10>
J 0
(-2890 4335);
DISPLAY 0.659574 (-2890 4335);
PAINT MONO (-2890 4335);
DISPLAY INVISIBLE (-2890 4335);
FORCEPROP 1 LASTPIN (-2900 4325) BN 10
J 2
(-2848 4333);
DISPLAY 0.617021 (-2848 4333);
PAINT PINK (-2848 4333);
FORCEPROP 1 LAST PATH I165
J 2
(-2848 4325);
DISPLAY 0.872340 (-2848 4325);
PAINT GREEN (-2848 4325);
DISPLAY INVISIBLE (-2848 4325);
FORCEPROP 1 LAST HDL_TAP TRUE
J 2
(-3175 4200);
DISPLAY 1.595745 (-3175 4200);
PAINT GREEN (-3175 4200);
DISPLAY INVISIBLE (-3175 4200);
FORCEPROP 1 LAST BODY_TYPE PLUMBING
J 2
(-2850 4275);
DISPLAY 1.595745 (-2850 4275);
PAINT GREEN (-2850 4275);
DISPLAY INVISIBLE (-2850 4275);
FORCEPROP 2 LAST CDS_LIB mstr_standard
J 0
(-2850 4325);
PAINT MONO (-2850 4325);
DISPLAY INVISIBLE (-2850 4325);
FORCEADD TAP..6
R 2
(-2850 4475);
FORCEPROP 3 LASTPIN (-2900 4475) SIG_NAME M_F_DQS_DP<13>
J 0
(-2890 4485);
DISPLAY 0.659574 (-2890 4485);
PAINT MONO (-2890 4485);
DISPLAY INVISIBLE (-2890 4485);
FORCEPROP 1 LASTPIN (-2900 4475) BN 13
J 2
(-2848 4483);
DISPLAY 0.617021 (-2848 4483);
PAINT PINK (-2848 4483);
FORCEPROP 1 LAST PATH I166
J 2
(-2848 4475);
DISPLAY 0.872340 (-2848 4475);
PAINT GREEN (-2848 4475);
DISPLAY INVISIBLE (-2848 4475);
FORCEPROP 1 LAST HDL_TAP TRUE
J 2
(-3175 4350);
DISPLAY 1.595745 (-3175 4350);
PAINT GREEN (-3175 4350);
DISPLAY INVISIBLE (-3175 4350);
FORCEPROP 1 LAST BODY_TYPE PLUMBING
J 2
(-2850 4425);
DISPLAY 1.595745 (-2850 4425);
PAINT GREEN (-2850 4425);
DISPLAY INVISIBLE (-2850 4425);
FORCEPROP 2 LAST CDS_LIB mstr_standard
J 0
(-2850 4475);
PAINT MONO (-2850 4475);
DISPLAY INVISIBLE (-2850 4475);
FORCEADD TAP..6
R 2
(-2850 4525);
FORCEPROP 3 LASTPIN (-2900 4525) SIG_NAME M_F_DQS_DP<14>
J 0
(-2890 4535);
DISPLAY 0.659574 (-2890 4535);
PAINT MONO (-2890 4535);
DISPLAY INVISIBLE (-2890 4535);
FORCEPROP 1 LASTPIN (-2900 4525) BN 14
J 2
(-2848 4533);
DISPLAY 0.617021 (-2848 4533);
PAINT PINK (-2848 4533);
FORCEPROP 1 LAST PATH I167
J 2
(-2848 4525);
DISPLAY 0.872340 (-2848 4525);
PAINT GREEN (-2848 4525);
DISPLAY INVISIBLE (-2848 4525);
FORCEPROP 1 LAST HDL_TAP TRUE
J 2
(-3175 4400);
DISPLAY 1.595745 (-3175 4400);
PAINT GREEN (-3175 4400);
DISPLAY INVISIBLE (-3175 4400);
FORCEPROP 1 LAST BODY_TYPE PLUMBING
J 2
(-2850 4475);
DISPLAY 1.595745 (-2850 4475);
PAINT GREEN (-2850 4475);
DISPLAY INVISIBLE (-2850 4475);
FORCEPROP 2 LAST CDS_LIB mstr_standard
J 0
(-2850 4525);
PAINT MONO (-2850 4525);
DISPLAY INVISIBLE (-2850 4525);
FORCEADD TAP..6
R 2
(-2850 4575);
FORCEPROP 3 LASTPIN (-2900 4575) SIG_NAME M_F_DQS_DP<15>
J 0
(-2890 4585);
DISPLAY 0.659574 (-2890 4585);
PAINT MONO (-2890 4585);
DISPLAY INVISIBLE (-2890 4585);
FORCEPROP 1 LASTPIN (-2900 4575) BN 15
J 2
(-2848 4583);
DISPLAY 0.617021 (-2848 4583);
PAINT PINK (-2848 4583);
FORCEPROP 1 LAST PATH I168
J 2
(-2848 4575);
DISPLAY 0.872340 (-2848 4575);
PAINT GREEN (-2848 4575);
DISPLAY INVISIBLE (-2848 4575);
FORCEPROP 1 LAST HDL_TAP TRUE
J 2
(-3175 4450);
DISPLAY 1.595745 (-3175 4450);
PAINT GREEN (-3175 4450);
DISPLAY INVISIBLE (-3175 4450);
FORCEPROP 1 LAST BODY_TYPE PLUMBING
J 2
(-2850 4525);
DISPLAY 1.595745 (-2850 4525);
PAINT GREEN (-2850 4525);
DISPLAY INVISIBLE (-2850 4525);
FORCEPROP 2 LAST CDS_LIB mstr_standard
J 0
(-2850 4575);
PAINT MONO (-2850 4575);
DISPLAY INVISIBLE (-2850 4575);
FORCEADD TAP..6
R 2
(-2850 4625);
FORCEPROP 3 LASTPIN (-2900 4625) SIG_NAME M_F_DQS_DP<16>
J 0
(-2890 4635);
DISPLAY 0.659574 (-2890 4635);
PAINT MONO (-2890 4635);
DISPLAY INVISIBLE (-2890 4635);
FORCEPROP 1 LASTPIN (-2900 4625) BN 16
J 2
(-2848 4633);
DISPLAY 0.617021 (-2848 4633);
PAINT PINK (-2848 4633);
FORCEPROP 1 LAST PATH I169
J 2
(-2848 4625);
DISPLAY 0.872340 (-2848 4625);
PAINT GREEN (-2848 4625);
DISPLAY INVISIBLE (-2848 4625);
FORCEPROP 1 LAST HDL_TAP TRUE
J 2
(-3175 4500);
DISPLAY 1.595745 (-3175 4500);
PAINT GREEN (-3175 4500);
DISPLAY INVISIBLE (-3175 4500);
FORCEPROP 1 LAST BODY_TYPE PLUMBING
J 2
(-2850 4575);
DISPLAY 1.595745 (-2850 4575);
PAINT GREEN (-2850 4575);
DISPLAY INVISIBLE (-2850 4575);
FORCEPROP 2 LAST CDS_LIB mstr_standard
J 0
(-2850 4625);
PAINT MONO (-2850 4625);
DISPLAY INVISIBLE (-2850 4625);
FORCEADD TAP..6
(-5575 1275);
FORCEPROP 3 LASTPIN (-5525 1275) SIG_NAME M_F_ECC<4>
J 0
(-5515 1285);
DISPLAY 0.659574 (-5515 1285);
PAINT MONO (-5515 1285);
DISPLAY INVISIBLE (-5515 1285);
FORCEPROP 1 LASTPIN (-5525 1275) BN 4
J 0
(-5577 1283);
DISPLAY 0.617021 (-5577 1283);
PAINT PINK (-5577 1283);
FORCEPROP 1 LAST PATH I17
J 0
(-5577 1275);
DISPLAY 0.872340 (-5577 1275);
PAINT GREEN (-5577 1275);
DISPLAY INVISIBLE (-5577 1275);
FORCEPROP 1 LAST HDL_TAP TRUE
J 0
(-5250 1150);
DISPLAY 1.595745 (-5250 1150);
PAINT GREEN (-5250 1150);
DISPLAY INVISIBLE (-5250 1150);
FORCEPROP 1 LAST BODY_TYPE PLUMBING
J 0
(-5575 1225);
DISPLAY 1.595745 (-5575 1225);
PAINT GREEN (-5575 1225);
DISPLAY INVISIBLE (-5575 1225);
FORCEPROP 2 LAST CDS_LIB mstr_standard
J 0
(-5575 1275);
PAINT MONO (-5575 1275);
DISPLAY INVISIBLE (-5575 1275);
FORCEADD TAP..6
R 2
(-2850 4675);
FORCEPROP 3 LASTPIN (-2900 4675) SIG_NAME M_F_DQS_DP<17>
J 0
(-2890 4685);
DISPLAY 0.659574 (-2890 4685);
PAINT MONO (-2890 4685);
DISPLAY INVISIBLE (-2890 4685);
FORCEPROP 1 LASTPIN (-2900 4675) BN 17
J 2
(-2848 4683);
DISPLAY 0.617021 (-2848 4683);
PAINT PINK (-2848 4683);
FORCEPROP 1 LAST PATH I170
J 2
(-2848 4675);
DISPLAY 0.872340 (-2848 4675);
PAINT GREEN (-2848 4675);
DISPLAY INVISIBLE (-2848 4675);
FORCEPROP 1 LAST HDL_TAP TRUE
J 2
(-3175 4550);
DISPLAY 1.595745 (-3175 4550);
PAINT GREEN (-3175 4550);
DISPLAY INVISIBLE (-3175 4550);
FORCEPROP 1 LAST BODY_TYPE PLUMBING
J 2
(-2850 4625);
DISPLAY 1.595745 (-2850 4625);
PAINT GREEN (-2850 4625);
DISPLAY INVISIBLE (-2850 4625);
FORCEPROP 2 LAST CDS_LIB mstr_standard
J 2
(-2850 4675);
PAINT MONO (-2850 4675);
DISPLAY INVISIBLE (-2850 4675);
FORCEADD OFFPAGE..3
(-2000 4750);
FORCEPROP 2 LAST $XR1 54 
J 0
(-1696 4750);
DISPLAY 0.638298 (-1696 4750);
PAINT MONO (-1696 4750);
FORCEPROP 2 LAST $XR0 53 
J 0
(-1786 4750);
DISPLAY 0.638298 (-1786 4750);
PAINT MONO (-1786 4750);
FORCEPROP 2 LAST PATH I171
J 0
(-1800 4825);
DISPLAY 1.021277 (-1800 4825);
PAINT ORANGE (-1800 4825);
DISPLAY INVISIBLE (-1800 4825);
FORCEPROP 1 LAST COMMENT_BODY TRUE
J 0
(-2050 4650);
DISPLAY 1.170213 (-2050 4650);
PAINT GREEN (-2050 4650);
DISPLAY INVISIBLE (-2050 4650);
FORCEPROP 1 LAST OFFPAGE TRUE
J 0
(-1675 4625);
DISPLAY 1.170213 (-1675 4625);
PAINT GREEN (-1675 4625);
DISPLAY INVISIBLE (-1675 4625);
FORCEPROP 2 LAST CDS_LIB mstr_standard
J 0
(-2000 4750);
PAINT MONO (-2000 4750);
DISPLAY INVISIBLE (-2000 4750);
FORCEADD SKX_EXT_B..8
(-4175 2575);
FORCEPROP 2 LASTPIN (-3325 4175) $PN DB29
J 0
(-3315 4185);
DISPLAY 0.617021 (-3315 4185);
PAINT ORANGE (-3315 4185);
FORCEPROP 2 LASTPIN (-5025 2875) $PN CT63
J 2
(-5035 2885);
DISPLAY 0.617021 (-5035 2885);
PAINT ORANGE (-5035 2885);
FORCEPROP 2 LASTPIN (-5025 2925) $PN CP67
J 2
(-5035 2935);
DISPLAY 0.617021 (-5035 2935);
PAINT ORANGE (-5035 2935);
FORCEPROP 2 LASTPIN (-3325 625) $PN DC62
J 0
(-3315 635);
DISPLAY 0.617021 (-3315 635);
PAINT ORANGE (-3315 635);
FORCEPROP 2 LASTPIN (-3325 575) $PN DD61
J 0
(-3315 585);
DISPLAY 0.617021 (-3315 585);
PAINT ORANGE (-3315 585);
FORCEPROP 2 LASTPIN (-3325 725) $PN DJ52
J 0
(-3315 735);
DISPLAY 0.617021 (-3315 735);
PAINT ORANGE (-3315 735);
FORCEPROP 2 LASTPIN (-3325 775) $PN DC56
J 0
(-3315 785);
DISPLAY 0.617021 (-3315 785);
PAINT ORANGE (-3315 785);
FORCEPROP 2 LASTPIN (-3325 825) $PN DA62
J 0
(-3315 835);
DISPLAY 0.617021 (-3315 835);
PAINT ORANGE (-3315 835);
FORCEPROP 2 LASTPIN (-3325 875) $PN DF61
J 0
(-3315 885);
DISPLAY 0.617021 (-3315 885);
PAINT ORANGE (-3315 885);
FORCEPROP 2 LASTPIN (-5025 525) $PN DF45
J 2
(-5035 535);
DISPLAY 0.617021 (-5035 535);
PAINT ORANGE (-5035 535);
FORCEPROP 2 LASTPIN (-3325 1675) $PN DG62
J 0
(-3315 1685);
DISPLAY 0.617021 (-3315 1685);
PAINT ORANGE (-3315 1685);
FORCEPROP 2 LASTPIN (-3325 1725) $PN DD63
J 0
(-3315 1735);
DISPLAY 0.617021 (-3315 1735);
PAINT ORANGE (-3315 1735);
FORCEPROP 2 LASTPIN (-3325 1775) $PN DK63
J 0
(-3315 1785);
DISPLAY 0.617021 (-3315 1785);
PAINT ORANGE (-3315 1785);
FORCEPROP 2 LASTPIN (-3325 1825) $PN DF63
J 0
(-3315 1835);
DISPLAY 0.617021 (-3315 1835);
PAINT ORANGE (-3315 1835);
FORCEPROP 2 LASTPIN (-5025 625) $PN DK55
J 2
(-5035 635);
DISPLAY 0.617021 (-5035 635);
PAINT ORANGE (-5035 635);
FORCEPROP 2 LASTPIN (-5025 675) $PN DF55
J 2
(-5035 685);
DISPLAY 0.617021 (-5035 685);
PAINT ORANGE (-5035 685);
FORCEPROP 2 LASTPIN (-5025 725) $PN DK57
J 2
(-5035 735);
DISPLAY 0.617021 (-5035 735);
PAINT ORANGE (-5035 735);
FORCEPROP 2 LASTPIN (-5025 775) $PN DF57
J 2
(-5035 785);
DISPLAY 0.617021 (-5035 785);
PAINT ORANGE (-5035 785);
FORCEPROP 2 LASTPIN (-5025 825) $PN DJ54
J 2
(-5035 835);
DISPLAY 0.617021 (-5035 835);
PAINT ORANGE (-5035 835);
FORCEPROP 2 LASTPIN (-5025 875) $PN DG54
J 2
(-5035 885);
DISPLAY 0.617021 (-5035 885);
PAINT ORANGE (-5035 885);
FORCEPROP 2 LASTPIN (-5025 925) $PN DJ56
J 2
(-5035 935);
DISPLAY 0.617021 (-5035 935);
PAINT ORANGE (-5035 935);
FORCEPROP 2 LASTPIN (-5025 975) $PN DG56
J 2
(-5035 985);
DISPLAY 0.617021 (-5035 985);
PAINT ORANGE (-5035 985);
FORCEPROP 2 LASTPIN (-3325 975) $PN DK51
J 0
(-3315 985);
DISPLAY 0.617021 (-3315 985);
PAINT ORANGE (-3315 985);
FORCEPROP 2 LASTPIN (-3325 1025) $PN DF49
J 0
(-3315 1035);
DISPLAY 0.617021 (-3315 1035);
PAINT ORANGE (-3315 1035);
FORCEPROP 2 LASTPIN (-3325 1075) $PN DJ46
J 0
(-3315 1085);
DISPLAY 0.617021 (-3315 1085);
PAINT ORANGE (-3315 1085);
FORCEPROP 2 LASTPIN (-3325 1125) $PN DG46
J 0
(-3315 1135);
DISPLAY 0.617021 (-3315 1135);
PAINT ORANGE (-3315 1135);
FORCEPROP 2 LASTPIN (-3325 1175) $PN DF51
J 0
(-3315 1185);
DISPLAY 0.617021 (-3315 1185);
PAINT ORANGE (-3315 1185);
FORCEPROP 2 LASTPIN (-3325 1225) $PN DJ48
J 0
(-3315 1235);
DISPLAY 0.617021 (-3315 1235);
PAINT ORANGE (-3315 1235);
FORCEPROP 2 LASTPIN (-3325 1275) $PN DM45
J 0
(-3315 1285);
DISPLAY 0.617021 (-3315 1285);
PAINT ORANGE (-3315 1285);
FORCEPROP 2 LASTPIN (-3325 1325) $PN DK45
J 0
(-3315 1335);
DISPLAY 0.617021 (-3315 1335);
PAINT ORANGE (-3315 1335);
FORCEPROP 2 LASTPIN (-5025 1525) $PN CR74
J 2
(-5035 1535);
DISPLAY 0.617021 (-5035 1535);
PAINT ORANGE (-5035 1535);
FORCEPROP 2 LASTPIN (-5025 1575) $PN CN76
J 2
(-5035 1585);
DISPLAY 0.617021 (-5035 1585);
PAINT ORANGE (-5035 1585);
FORCEPROP 2 LASTPIN (-5025 1625) $PN CW76
J 2
(-5035 1635);
DISPLAY 0.617021 (-5035 1635);
PAINT ORANGE (-5035 1635);
FORCEPROP 2 LASTPIN (-5025 1675) $PN CV77
J 2
(-5035 1685);
DISPLAY 0.617021 (-5035 1685);
PAINT ORANGE (-5035 1685);
FORCEPROP 2 LASTPIN (-5025 1725) $PN CN74
J 2
(-5035 1735);
DISPLAY 0.617021 (-5035 1735);
PAINT ORANGE (-5035 1735);
FORCEPROP 2 LASTPIN (-5025 1775) $PN CM75
J 2
(-5035 1785);
DISPLAY 0.617021 (-5035 1785);
PAINT ORANGE (-5035 1785);
FORCEPROP 2 LASTPIN (-5025 1825) $PN CV75
J 2
(-5035 1835);
DISPLAY 0.617021 (-5035 1835);
PAINT ORANGE (-5035 1835);
FORCEPROP 2 LASTPIN (-5025 1875) $PN CT77
J 2
(-5035 1885);
DISPLAY 0.617021 (-5035 1885);
PAINT ORANGE (-5035 1885);
FORCEPROP 2 LASTPIN (-5025 1925) $PN DE74
J 2
(-5035 1935);
DISPLAY 0.617021 (-5035 1935);
PAINT ORANGE (-5035 1935);
FORCEPROP 2 LASTPIN (-5025 1975) $PN DC76
J 2
(-5035 1985);
DISPLAY 0.617021 (-5035 1985);
PAINT ORANGE (-5035 1985);
FORCEPROP 2 LASTPIN (-5025 2025) $PN DH75
J 2
(-5035 2035);
DISPLAY 0.617021 (-5035 2035);
PAINT ORANGE (-5035 2035);
FORCEPROP 2 LASTPIN (-5025 2075) $PN DJ76
J 2
(-5035 2085);
DISPLAY 0.617021 (-5035 2085);
PAINT ORANGE (-5035 2085);
FORCEPROP 2 LASTPIN (-5025 2125) $PN DC74
J 2
(-5035 2135);
DISPLAY 0.617021 (-5035 2135);
PAINT ORANGE (-5035 2135);
FORCEPROP 2 LASTPIN (-5025 2175) $PN DB75
J 2
(-5035 2185);
DISPLAY 0.617021 (-5035 2185);
PAINT ORANGE (-5035 2185);
FORCEPROP 2 LASTPIN (-5025 2225) $PN DF77
J 2
(-5035 2235);
DISPLAY 0.617021 (-5035 2235);
PAINT ORANGE (-5035 2235);
FORCEPROP 2 LASTPIN (-5025 2275) $PN DH77
J 2
(-5035 2285);
DISPLAY 0.617021 (-5035 2285);
PAINT ORANGE (-5035 2285);
FORCEPROP 2 LASTPIN (-5025 2325) $PN DG70
J 2
(-5035 2335);
DISPLAY 0.617021 (-5035 2335);
PAINT ORANGE (-5035 2335);
FORCEPROP 2 LASTPIN (-5025 2375) $PN DJ72
J 2
(-5035 2385);
DISPLAY 0.617021 (-5035 2385);
PAINT ORANGE (-5035 2385);
FORCEPROP 2 LASTPIN (-5025 2425) $PN DM69
J 2
(-5035 2435);
DISPLAY 0.617021 (-5035 2435);
PAINT ORANGE (-5035 2435);
FORCEPROP 2 LASTPIN (-5025 2475) $PN DN70
J 2
(-5035 2485);
DISPLAY 0.617021 (-5035 2485);
PAINT ORANGE (-5035 2485);
FORCEPROP 2 LASTPIN (-5025 2525) $PN DF71
J 2
(-5035 2535);
DISPLAY 0.617021 (-5035 2535);
PAINT ORANGE (-5035 2535);
FORCEPROP 2 LASTPIN (-5025 2575) $PN DG72
J 2
(-5035 2585);
DISPLAY 0.617021 (-5035 2585);
PAINT ORANGE (-5035 2585);
FORCEPROP 2 LASTPIN (-5025 2625) $PN DK69
J 2
(-5035 2635);
DISPLAY 0.617021 (-5035 2635);
PAINT ORANGE (-5035 2635);
FORCEPROP 2 LASTPIN (-5025 2675) $PN DM71
J 2
(-5035 2685);
DISPLAY 0.617021 (-5035 2685);
PAINT ORANGE (-5035 2685);
FORCEPROP 2 LASTPIN (-5025 2725) $PN CN66
J 2
(-5035 2735);
DISPLAY 0.617021 (-5035 2735);
PAINT ORANGE (-5035 2735);
FORCEPROP 2 LASTPIN (-5025 2775) $PN CU66
J 2
(-5035 2785);
DISPLAY 0.617021 (-5035 2785);
PAINT ORANGE (-5035 2785);
FORCEPROP 2 LASTPIN (-5025 2825) $PN CP63
J 2
(-5035 2835);
DISPLAY 0.617021 (-5035 2835);
PAINT ORANGE (-5035 2835);
FORCEPROP 2 LASTPIN (-5025 2975) $PN CT67
J 2
(-5035 2985);
DISPLAY 0.617021 (-5035 2985);
PAINT ORANGE (-5035 2985);
FORCEPROP 2 LASTPIN (-5025 3025) $PN CN64
J 2
(-5035 3035);
DISPLAY 0.617021 (-5035 3035);
PAINT ORANGE (-5035 3035);
FORCEPROP 2 LASTPIN (-5025 3075) $PN CU64
J 2
(-5035 3085);
DISPLAY 0.617021 (-5035 3085);
PAINT ORANGE (-5035 3085);
FORCEPROP 2 LASTPIN (-5025 3125) $PN DD41
J 2
(-5035 3135);
DISPLAY 0.617021 (-5035 3135);
PAINT ORANGE (-5035 3135);
FORCEPROP 2 LASTPIN (-5025 3175) $PN DG42
J 2
(-5035 3185);
DISPLAY 0.617021 (-5035 3185);
PAINT ORANGE (-5035 3185);
FORCEPROP 2 LASTPIN (-5025 3225) $PN DE38
J 2
(-5035 3235);
DISPLAY 0.617021 (-5035 3235);
PAINT ORANGE (-5035 3235);
FORCEPROP 2 LASTPIN (-5025 3275) $PN DG38
J 2
(-5035 3285);
DISPLAY 0.617021 (-5035 3285);
PAINT ORANGE (-5035 3285);
FORCEPROP 2 LASTPIN (-5025 3325) $PN DA42
J 2
(-5035 3335);
DISPLAY 0.617021 (-5035 3335);
PAINT ORANGE (-5035 3335);
FORCEPROP 2 LASTPIN (-5025 3375) $PN DE42
J 2
(-5035 3385);
DISPLAY 0.617021 (-5035 3385);
PAINT ORANGE (-5035 3385);
FORCEPROP 2 LASTPIN (-5025 3425) $PN DD39
J 2
(-5035 3435);
DISPLAY 0.617021 (-5035 3435);
PAINT ORANGE (-5035 3435);
FORCEPROP 2 LASTPIN (-5025 3475) $PN DH39
J 2
(-5035 3485);
DISPLAY 0.617021 (-5035 3485);
PAINT ORANGE (-5035 3485);
FORCEPROP 2 LASTPIN (-5025 3525) $PN DF33
J 2
(-5035 3535);
DISPLAY 0.617021 (-5035 3535);
PAINT ORANGE (-5035 3535);
FORCEPROP 2 LASTPIN (-5025 3575) $PN DK33
J 2
(-5035 3585);
DISPLAY 0.617021 (-5035 3585);
PAINT ORANGE (-5035 3585);
FORCEPROP 2 LASTPIN (-5025 3625) $PN DG30
J 2
(-5035 3635);
DISPLAY 0.617021 (-5035 3635);
PAINT ORANGE (-5035 3635);
FORCEPROP 2 LASTPIN (-5025 3675) $PN DJ30
J 2
(-5035 3685);
DISPLAY 0.617021 (-5035 3685);
PAINT ORANGE (-5035 3685);
FORCEPROP 2 LASTPIN (-5025 3725) $PN DG34
J 2
(-5035 3735);
DISPLAY 0.617021 (-5035 3735);
PAINT ORANGE (-5035 3735);
FORCEPROP 2 LASTPIN (-5025 3775) $PN DJ34
J 2
(-5035 3785);
DISPLAY 0.617021 (-5035 3785);
PAINT ORANGE (-5035 3785);
FORCEPROP 2 LASTPIN (-5025 3825) $PN DF31
J 2
(-5035 3835);
DISPLAY 0.617021 (-5035 3835);
PAINT ORANGE (-5035 3835);
FORCEPROP 2 LASTPIN (-5025 3875) $PN DK31
J 2
(-5035 3885);
DISPLAY 0.617021 (-5035 3885);
PAINT ORANGE (-5035 3885);
FORCEPROP 2 LASTPIN (-5025 3925) $PN CW36
J 2
(-5035 3935);
DISPLAY 0.617021 (-5035 3935);
PAINT ORANGE (-5035 3935);
FORCEPROP 2 LASTPIN (-5025 4025) $PN CY33
J 2
(-5035 4035);
DISPLAY 0.617021 (-5035 4035);
PAINT ORANGE (-5035 4035);
FORCEPROP 2 LASTPIN (-5025 4075) $PN DB33
J 2
(-5035 4085);
DISPLAY 0.617021 (-5035 4085);
PAINT ORANGE (-5035 4085);
FORCEPROP 2 LASTPIN (-5025 4125) $PN CY37
J 2
(-5035 4135);
DISPLAY 0.617021 (-5035 4135);
PAINT ORANGE (-5035 4135);
FORCEPROP 2 LASTPIN (-5025 4175) $PN DB37
J 2
(-5035 4185);
DISPLAY 0.617021 (-5035 4185);
PAINT ORANGE (-5035 4185);
FORCEPROP 2 LASTPIN (-5025 4225) $PN CW34
J 2
(-5035 4235);
DISPLAY 0.617021 (-5035 4235);
PAINT ORANGE (-5035 4235);
FORCEPROP 2 LASTPIN (-5025 4275) $PN DC34
J 2
(-5035 4285);
DISPLAY 0.617021 (-5035 4285);
PAINT ORANGE (-5035 4285);
FORCEPROP 2 LASTPIN (-5025 4325) $PN CW30
J 2
(-5035 4335);
DISPLAY 0.617021 (-5035 4335);
PAINT ORANGE (-5035 4335);
FORCEPROP 2 LASTPIN (-5025 4375) $PN DC30
J 2
(-5035 4385);
DISPLAY 0.617021 (-5035 4385);
PAINT ORANGE (-5035 4385);
FORCEPROP 2 LASTPIN (-5025 4425) $PN CY27
J 2
(-5035 4435);
DISPLAY 0.617021 (-5035 4435);
PAINT ORANGE (-5035 4435);
FORCEPROP 2 LASTPIN (-5025 4475) $PN DB27
J 2
(-5035 4485);
DISPLAY 0.617021 (-5035 4485);
PAINT ORANGE (-5035 4485);
FORCEPROP 2 LASTPIN (-5025 4525) $PN CY31
J 2
(-5035 4535);
DISPLAY 0.617021 (-5035 4535);
PAINT ORANGE (-5035 4535);
FORCEPROP 2 LASTPIN (-5025 4575) $PN DB31
J 2
(-5035 4585);
DISPLAY 0.617021 (-5035 4585);
PAINT ORANGE (-5035 4585);
FORCEPROP 2 LASTPIN (-5025 4625) $PN CW28
J 2
(-5035 4635);
DISPLAY 0.617021 (-5035 4635);
PAINT ORANGE (-5035 4635);
FORCEPROP 2 LASTPIN (-5025 4675) $PN DC28
J 2
(-5035 4685);
DISPLAY 0.617021 (-5035 4685);
PAINT ORANGE (-5035 4685);
FORCEPROP 2 LASTPIN (-3325 2875) $PN CP77
J 0
(-3315 2885);
DISPLAY 0.617021 (-3315 2885);
PAINT ORANGE (-3315 2885);
FORCEPROP 2 LASTPIN (-3325 2925) $PN DD77
J 0
(-3315 2935);
DISPLAY 0.617021 (-3315 2935);
PAINT ORANGE (-3315 2935);
FORCEPROP 2 LASTPIN (-3325 2975) $PN DL72
J 0
(-3315 2985);
DISPLAY 0.617021 (-3315 2985);
PAINT ORANGE (-3315 2985);
FORCEPROP 2 LASTPIN (-3325 3025) $PN CV65
J 0
(-3315 3035);
DISPLAY 0.617021 (-3315 3035);
PAINT ORANGE (-3315 3035);
FORCEPROP 2 LASTPIN (-3325 3075) $PN DG40
J 0
(-3315 3085);
DISPLAY 0.617021 (-3315 3085);
PAINT ORANGE (-3315 3085);
FORCEPROP 2 LASTPIN (-3325 3125) $PN DL32
J 0
(-3315 3135);
DISPLAY 0.617021 (-3315 3135);
PAINT ORANGE (-3315 3135);
FORCEPROP 2 LASTPIN (-3325 3175) $PN DD35
J 0
(-3315 3185);
DISPLAY 0.617021 (-3315 3185);
PAINT ORANGE (-3315 3185);
FORCEPROP 2 LASTPIN (-3325 3225) $PN DD29
J 0
(-3315 3235);
DISPLAY 0.617021 (-3315 3235);
PAINT ORANGE (-3315 3235);
FORCEPROP 2 LASTPIN (-3325 3275) $PN CN70
J 0
(-3315 3285);
DISPLAY 0.617021 (-3315 3285);
PAINT ORANGE (-3315 3285);
FORCEPROP 2 LASTPIN (-3325 3325) $PN CT75
J 0
(-3315 3335);
DISPLAY 0.617021 (-3315 3335);
PAINT ORANGE (-3315 3335);
FORCEPROP 2 LASTPIN (-3325 3375) $PN DF75
J 0
(-3315 3385);
DISPLAY 0.617021 (-3315 3385);
PAINT ORANGE (-3315 3385);
FORCEPROP 2 LASTPIN (-3325 3425) $PN DJ70
J 0
(-3315 3435);
DISPLAY 0.617021 (-3315 3435);
PAINT ORANGE (-3315 3435);
FORCEPROP 2 LASTPIN (-3325 3475) $PN CP65
J 0
(-3315 3485);
DISPLAY 0.617021 (-3315 3485);
PAINT ORANGE (-3315 3485);
FORCEPROP 2 LASTPIN (-3325 3525) $PN DE40
J 0
(-3315 3535);
DISPLAY 0.617021 (-3315 3535);
PAINT ORANGE (-3315 3535);
FORCEPROP 2 LASTPIN (-3325 3575) $PN DG32
J 0
(-3315 3585);
DISPLAY 0.617021 (-3315 3585);
PAINT ORANGE (-3315 3585);
FORCEPROP 2 LASTPIN (-3325 3675) $PN CY29
J 0
(-3315 3685);
DISPLAY 0.617021 (-3315 3685);
PAINT ORANGE (-3315 3685);
FORCEPROP 2 LASTPIN (-3325 3725) $PN CJ70
J 0
(-3315 3735);
DISPLAY 0.617021 (-3315 3735);
PAINT ORANGE (-3315 3735);
FORCEPROP 2 LASTPIN (-3325 3825) $PN CR76
J 0
(-3315 3835);
DISPLAY 0.617021 (-3315 3835);
PAINT ORANGE (-3315 3835);
FORCEPROP 2 LASTPIN (-3325 3875) $PN DE76
J 0
(-3315 3885);
DISPLAY 0.617021 (-3315 3885);
PAINT ORANGE (-3315 3885);
FORCEPROP 2 LASTPIN (-3325 3925) $PN DK71
J 0
(-3315 3935);
DISPLAY 0.617021 (-3315 3935);
PAINT ORANGE (-3315 3935);
FORCEPROP 2 LASTPIN (-3325 3975) $PN CT65
J 0
(-3315 3985);
DISPLAY 0.617021 (-3315 3985);
PAINT ORANGE (-3315 3985);
FORCEPROP 2 LASTPIN (-3325 4025) $PN DJ40
J 0
(-3315 4035);
DISPLAY 0.617021 (-3315 4035);
PAINT ORANGE (-3315 4035);
FORCEPROP 2 LASTPIN (-3325 4075) $PN DJ32
J 0
(-3315 4085);
DISPLAY 0.617021 (-3315 4085);
PAINT ORANGE (-3315 4085);
FORCEPROP 2 LASTPIN (-3325 4125) $PN DB35
J 0
(-3315 4135);
DISPLAY 0.617021 (-3315 4135);
PAINT ORANGE (-3315 4135);
FORCEPROP 2 LASTPIN (-3325 4225) $PN CL70
J 0
(-3315 4235);
DISPLAY 0.617021 (-3315 4235);
PAINT ORANGE (-3315 4235);
FORCEPROP 2 LASTPIN (-3325 4275) $PN CU74
J 0
(-3315 4285);
DISPLAY 0.617021 (-3315 4285);
PAINT ORANGE (-3315 4285);
FORCEPROP 2 LASTPIN (-3325 4325) $PN DG74
J 0
(-3315 4335);
DISPLAY 0.617021 (-3315 4335);
PAINT ORANGE (-3315 4335);
FORCEPROP 2 LASTPIN (-3325 4375) $PN DH69
J 0
(-3315 4385);
DISPLAY 0.617021 (-3315 4385);
PAINT ORANGE (-3315 4385);
FORCEPROP 2 LASTPIN (-3325 4425) $PN CM65
J 0
(-3315 4435);
DISPLAY 0.617021 (-3315 4435);
PAINT ORANGE (-3315 4435);
FORCEPROP 2 LASTPIN (-3325 4475) $PN DC40
J 0
(-3315 4485);
DISPLAY 0.617021 (-3315 4485);
PAINT ORANGE (-3315 4485);
FORCEPROP 2 LASTPIN (-3325 4525) $PN DE32
J 0
(-3315 4535);
DISPLAY 0.617021 (-3315 4535);
PAINT ORANGE (-3315 4535);
FORCEPROP 2 LASTPIN (-3325 4575) $PN CV35
J 0
(-3315 4585);
DISPLAY 0.617021 (-3315 4585);
PAINT ORANGE (-3315 4585);
FORCEPROP 2 LASTPIN (-3325 4625) $PN CV29
J 0
(-3315 4635);
DISPLAY 0.617021 (-3315 4635);
PAINT ORANGE (-3315 4635);
FORCEPROP 2 LASTPIN (-3325 4675) $PN CG70
J 0
(-3315 4685);
DISPLAY 0.617021 (-3315 4685);
PAINT ORANGE (-3315 4685);
FORCEPROP 2 LASTPIN (-5025 1075) $PN CH71
J 2
(-5035 1085);
DISPLAY 0.617021 (-5035 1085);
PAINT ORANGE (-5035 1085);
FORCEPROP 2 LASTPIN (-5025 1125) $PN CM71
J 2
(-5035 1135);
DISPLAY 0.617021 (-5035 1135);
PAINT ORANGE (-5035 1135);
FORCEPROP 2 LASTPIN (-5025 1175) $PN CJ68
J 2
(-5035 1185);
DISPLAY 0.617021 (-5035 1185);
PAINT ORANGE (-5035 1185);
FORCEPROP 2 LASTPIN (-5025 1225) $PN CL68
J 2
(-5035 1235);
DISPLAY 0.617021 (-5035 1235);
PAINT ORANGE (-5035 1235);
FORCEPROP 2 LASTPIN (-5025 1275) $PN CJ72
J 2
(-5035 1285);
DISPLAY 0.617021 (-5035 1285);
PAINT ORANGE (-5035 1285);
FORCEPROP 2 LASTPIN (-5025 1325) $PN CL72
J 2
(-5035 1335);
DISPLAY 0.617021 (-5035 1335);
PAINT ORANGE (-5035 1335);
FORCEPROP 2 LASTPIN (-5025 1375) $PN CH69
J 2
(-5035 1385);
DISPLAY 0.617021 (-5035 1385);
PAINT ORANGE (-5035 1385);
FORCEPROP 2 LASTPIN (-5025 1425) $PN CM69
J 2
(-5035 1435);
DISPLAY 0.617021 (-5035 1435);
PAINT ORANGE (-5035 1435);
FORCEPROP 2 LASTPIN (-3325 1925) $PN DF53
J 0
(-3315 1935);
DISPLAY 0.617021 (-3315 1935);
PAINT ORANGE (-3315 1935);
FORCEPROP 2 LASTPIN (-3325 1975) $PN DC58
J 0
(-3315 1985);
DISPLAY 0.617021 (-3315 1985);
PAINT ORANGE (-3315 1985);
FORCEPROP 2 LASTPIN (-3325 2025) $PN DD57
J 0
(-3315 2035);
DISPLAY 0.617021 (-3315 2035);
PAINT ORANGE (-3315 2035);
FORCEPROP 2 LASTPIN (-3325 2075) $PN DG58
J 0
(-3315 2085);
DISPLAY 0.617021 (-3315 2085);
PAINT ORANGE (-3315 2085);
FORCEPROP 2 LASTPIN (-3325 2125) $PN DJ58
J 0
(-3315 2135);
DISPLAY 0.617021 (-3315 2135);
PAINT ORANGE (-3315 2135);
FORCEPROP 2 LASTPIN (-3325 2175) $PN DF59
J 0
(-3315 2185);
DISPLAY 0.617021 (-3315 2185);
PAINT ORANGE (-3315 2185);
FORCEPROP 2 LASTPIN (-3325 2225) $PN DK59
J 0
(-3315 2235);
DISPLAY 0.617021 (-3315 2235);
PAINT ORANGE (-3315 2235);
FORCEPROP 2 LASTPIN (-3325 2275) $PN DC60
J 0
(-3315 2285);
DISPLAY 0.617021 (-3315 2285);
PAINT ORANGE (-3315 2285);
FORCEPROP 2 LASTPIN (-3325 2325) $PN DD59
J 0
(-3315 2335);
DISPLAY 0.617021 (-3315 2335);
PAINT ORANGE (-3315 2335);
FORCEPROP 2 LASTPIN (-3325 2375) $PN DA58
J 0
(-3315 2385);
DISPLAY 0.617021 (-3315 2385);
PAINT ORANGE (-3315 2385);
FORCEPROP 2 LASTPIN (-3325 2425) $PN DD55
J 0
(-3315 2435);
DISPLAY 0.617021 (-3315 2435);
PAINT ORANGE (-3315 2435);
FORCEPROP 2 LASTPIN (-3325 2475) $PN DA60
J 0
(-3315 2485);
DISPLAY 0.617021 (-3315 2485);
PAINT ORANGE (-3315 2485);
FORCEPROP 2 LASTPIN (-3325 2525) $PN DG60
J 0
(-3315 2535);
DISPLAY 0.617021 (-3315 2535);
PAINT ORANGE (-3315 2535);
FORCEPROP 2 LASTPIN (-3325 2575) $PN DD53
J 0
(-3315 2585);
DISPLAY 0.617021 (-3315 2585);
PAINT ORANGE (-3315 2585);
FORCEPROP 2 LASTPIN (-3325 2625) $PN DJ50
J 0
(-3315 2635);
DISPLAY 0.617021 (-3315 2635);
PAINT ORANGE (-3315 2635);
FORCEPROP 2 LASTPIN (-3325 2675) $PN DC54
J 0
(-3315 2685);
DISPLAY 0.617021 (-3315 2685);
PAINT ORANGE (-3315 2685);
FORCEPROP 2 LASTPIN (-3325 2725) $PN DG52
J 0
(-3315 2735);
DISPLAY 0.617021 (-3315 2735);
PAINT ORANGE (-3315 2735);
FORCEPROP 2 LASTPIN (-3325 2775) $PN DE46
J 0
(-3315 2785);
DISPLAY 0.617021 (-3315 2785);
PAINT ORANGE (-3315 2785);
FORCEPROP 2 LASTPIN (-3325 1425) $PN DG50
J 0
(-3315 1435);
DISPLAY 0.617021 (-3315 1435);
PAINT ORANGE (-3315 1435);
FORCEPROP 2 LASTPIN (-3325 1475) $PN DG48
J 0
(-3315 1485);
DISPLAY 0.617021 (-3315 1485);
PAINT ORANGE (-3315 1485);
FORCEPROP 2 LASTPIN (-3325 1525) $PN DK49
J 0
(-3315 1535);
DISPLAY 0.617021 (-3315 1535);
PAINT ORANGE (-3315 1535);
FORCEPROP 2 LASTPIN (-3325 1575) $PN DF47
J 0
(-3315 1585);
DISPLAY 0.617021 (-3315 1585);
PAINT ORANGE (-3315 1585);
FORCEPROP 2 LASTPIN (-3325 525) $PN DK53
J 0
(-3315 535);
DISPLAY 0.617021 (-3315 535);
PAINT ORANGE (-3315 535);
FORCEPROP 1 LAST MATERIAL IC
J 0
(-4975 4875);
DISPLAY 0.617021 (-4975 4875);
PAINT SKYBLUE (-4975 4875);
FORCEPROP 1 LAST PART_NUMBER TBD
J 0
(-4975 325);
DISPLAY 0.617021 (-4975 325);
PAINT BLUE (-4975 325);
FORCEPROP 1 LAST LOCATION U5D1
J 0
(-4975 4925);
DISPLAY 0.617021 (-4975 4925);
PAINT AQUA (-4975 4925);
FORCEPROP 2 LASTPIN (-5025 3975) $PN DC36
J 2
(-5035 3985);
DISPLAY 0.617021 (-5035 3985);
PAINT ORANGE (-5035 3985);
FORCEPROP 2 LASTPIN (-3325 3625) $PN CY35
J 0
(-3315 3635);
DISPLAY 0.617021 (-3315 3635);
PAINT ORANGE (-3315 3635);
FORCEPROP 0 LAST ROOM CPU0
J 0
(-4975 5025);
DISPLAY 1.021277 (-4975 5025);
PAINT ORANGE (-4975 5025);
DISPLAY INVISIBLE (-4975 5025);
FORCEPROP 1 LAST PATH I172
J 0
(-4175 4875);
PAINT GREEN (-4175 4875);
DISPLAY INVISIBLE (-4175 4875);
FORCEPROP 2 LAST CDS_LOCATION U5D1
J 0
(-4975 4925);
DISPLAY 0.617021 (-4975 4925);
PAINT AQUA (-4975 4925);
DISPLAY INVISIBLE (-4975 4925);
FORCEPROP 2 LAST SEC 8
J 0
(-4975 4975);
DISPLAY 0.680851 (-4975 4975);
PAINT MONO (-4975 4975);
DISPLAY INVISIBLE (-4975 4975);
FORCEPROP 2 LAST SEC_TYPE BGA1
J 0
(-4975 4975);
DISPLAY 1.021277 (-4975 4975);
PAINT ORANGE (-4975 4975);
DISPLAY INVISIBLE (-4975 4975);
FORCEPROP 2 LAST CDS_LIB chpset_lib
J 0
(-4175 2575);
PAINT ORANGE (-4175 2575);
DISPLAY INVISIBLE (-4175 2575);
FORCEPROP 1 LAST PACK_TYPE BGA1
J 0
(-4975 4975);
PAINT SKYBLUE (-4975 4975);
DISPLAY INVISIBLE (-4975 4975);
FORCEADD TAP..6
(-5575 1325);
FORCEPROP 3 LASTPIN (-5525 1325) SIG_NAME M_F_ECC<5>
J 0
(-5515 1335);
DISPLAY 0.659574 (-5515 1335);
PAINT MONO (-5515 1335);
DISPLAY INVISIBLE (-5515 1335);
FORCEPROP 1 LASTPIN (-5525 1325) BN 5
J 0
(-5577 1333);
DISPLAY 0.617021 (-5577 1333);
PAINT PINK (-5577 1333);
FORCEPROP 1 LAST PATH I18
J 0
(-5577 1325);
DISPLAY 0.872340 (-5577 1325);
PAINT GREEN (-5577 1325);
DISPLAY INVISIBLE (-5577 1325);
FORCEPROP 1 LAST HDL_TAP TRUE
J 0
(-5250 1200);
DISPLAY 1.595745 (-5250 1200);
PAINT GREEN (-5250 1200);
DISPLAY INVISIBLE (-5250 1200);
FORCEPROP 1 LAST BODY_TYPE PLUMBING
J 0
(-5575 1275);
DISPLAY 1.595745 (-5575 1275);
PAINT GREEN (-5575 1275);
DISPLAY INVISIBLE (-5575 1275);
FORCEPROP 2 LAST CDS_LIB mstr_standard
J 0
(-5575 1325);
PAINT MONO (-5575 1325);
DISPLAY INVISIBLE (-5575 1325);
FORCEADD TAP..6
(-5575 1375);
FORCEPROP 3 LASTPIN (-5525 1375) SIG_NAME M_F_ECC<6>
J 0
(-5515 1385);
DISPLAY 0.659574 (-5515 1385);
PAINT MONO (-5515 1385);
DISPLAY INVISIBLE (-5515 1385);
FORCEPROP 1 LASTPIN (-5525 1375) BN 6
J 0
(-5577 1383);
DISPLAY 0.617021 (-5577 1383);
PAINT PINK (-5577 1383);
FORCEPROP 1 LAST PATH I19
J 0
(-5577 1375);
DISPLAY 0.872340 (-5577 1375);
PAINT GREEN (-5577 1375);
DISPLAY INVISIBLE (-5577 1375);
FORCEPROP 1 LAST HDL_TAP TRUE
J 0
(-5250 1250);
DISPLAY 1.595745 (-5250 1250);
PAINT GREEN (-5250 1250);
DISPLAY INVISIBLE (-5250 1250);
FORCEPROP 1 LAST BODY_TYPE PLUMBING
J 0
(-5575 1325);
DISPLAY 1.595745 (-5575 1325);
PAINT GREEN (-5575 1325);
DISPLAY INVISIBLE (-5575 1325);
FORCEPROP 2 LAST CDS_LIB mstr_standard
J 0
(-5575 1375);
PAINT MONO (-5575 1375);
DISPLAY INVISIBLE (-5575 1375);
FORCEADD OFFPAGE..5
(-6425 825);
FORCEPROP 2 LAST $XR1 54 
J 0
(-6769 825);
DISPLAY 0.638298 (-6769 825);
PAINT MONO (-6769 825);
FORCEPROP 2 LAST $XR0 53 
J 0
(-6679 825);
DISPLAY 0.638298 (-6679 825);
PAINT MONO (-6679 825);
FORCEPROP 2 LAST PATH I2
J 0
(-6375 900);
DISPLAY 1.021277 (-6375 900);
PAINT ORANGE (-6375 900);
DISPLAY INVISIBLE (-6375 900);
FORCEPROP 1 LAST COMMENT_BODY TRUE
J 0
(-6325 750);
DISPLAY 1.170213 (-6325 750);
PAINT GREEN (-6325 750);
DISPLAY INVISIBLE (-6325 750);
FORCEPROP 1 LAST OFFPAGE TRUE
J 0
(-6100 700);
DISPLAY 1.170213 (-6100 700);
PAINT GREEN (-6100 700);
DISPLAY INVISIBLE (-6100 700);
FORCEPROP 2 LAST CDS_LIB mstr_standard
J 0
(-6425 825);
PAINT MONO (-6425 825);
DISPLAY INVISIBLE (-6425 825);
FORCEADD TAP..6
(-5575 1425);
FORCEPROP 3 LASTPIN (-5525 1425) SIG_NAME M_F_ECC<7>
J 0
(-5515 1435);
DISPLAY 0.659574 (-5515 1435);
PAINT MONO (-5515 1435);
DISPLAY INVISIBLE (-5515 1435);
FORCEPROP 1 LASTPIN (-5525 1425) BN 7
J 0
(-5577 1433);
DISPLAY 0.617021 (-5577 1433);
PAINT PINK (-5577 1433);
FORCEPROP 1 LAST PATH I20
J 0
(-5577 1425);
DISPLAY 0.872340 (-5577 1425);
PAINT GREEN (-5577 1425);
DISPLAY INVISIBLE (-5577 1425);
FORCEPROP 1 LAST HDL_TAP TRUE
J 0
(-5250 1300);
DISPLAY 1.595745 (-5250 1300);
PAINT GREEN (-5250 1300);
DISPLAY INVISIBLE (-5250 1300);
FORCEPROP 1 LAST BODY_TYPE PLUMBING
J 0
(-5575 1375);
DISPLAY 1.595745 (-5575 1375);
PAINT GREEN (-5575 1375);
DISPLAY INVISIBLE (-5575 1375);
FORCEPROP 2 LAST CDS_LIB mstr_standard
J 0
(-5575 1425);
PAINT MONO (-5575 1425);
DISPLAY INVISIBLE (-5575 1425);
FORCEADD TAP..6
(-5575 1575);
FORCEPROP 3 LASTPIN (-5525 1575) SIG_NAME M_F_DQ<1>
J 0
(-5515 1585);
DISPLAY 0.659574 (-5515 1585);
PAINT MONO (-5515 1585);
DISPLAY INVISIBLE (-5515 1585);
FORCEPROP 1 LASTPIN (-5525 1575) BN 1
J 0
(-5577 1583);
DISPLAY 0.617021 (-5577 1583);
PAINT PINK (-5577 1583);
FORCEPROP 1 LAST PATH I21
J 0
(-5577 1575);
DISPLAY 0.872340 (-5577 1575);
PAINT GREEN (-5577 1575);
DISPLAY INVISIBLE (-5577 1575);
FORCEPROP 1 LAST HDL_TAP TRUE
J 0
(-5250 1450);
DISPLAY 1.595745 (-5250 1450);
PAINT GREEN (-5250 1450);
DISPLAY INVISIBLE (-5250 1450);
FORCEPROP 1 LAST BODY_TYPE PLUMBING
J 0
(-5575 1525);
DISPLAY 1.595745 (-5575 1525);
PAINT GREEN (-5575 1525);
DISPLAY INVISIBLE (-5575 1525);
FORCEPROP 2 LAST CDS_LIB mstr_standard
J 0
(-5575 1575);
PAINT MONO (-5575 1575);
DISPLAY INVISIBLE (-5575 1575);
FORCEADD TAP..6
(-5575 1525);
FORCEPROP 3 LASTPIN (-5525 1525) SIG_NAME M_F_DQ<0>
J 0
(-5515 1535);
DISPLAY 0.659574 (-5515 1535);
PAINT MONO (-5515 1535);
DISPLAY INVISIBLE (-5515 1535);
FORCEPROP 1 LASTPIN (-5525 1525) BN 0
J 0
(-5577 1533);
DISPLAY 0.617021 (-5577 1533);
PAINT PINK (-5577 1533);
FORCEPROP 1 LAST PATH I22
J 0
(-5577 1525);
DISPLAY 0.872340 (-5577 1525);
PAINT GREEN (-5577 1525);
DISPLAY INVISIBLE (-5577 1525);
FORCEPROP 1 LAST HDL_TAP TRUE
J 0
(-5250 1400);
DISPLAY 1.595745 (-5250 1400);
PAINT GREEN (-5250 1400);
DISPLAY INVISIBLE (-5250 1400);
FORCEPROP 1 LAST BODY_TYPE PLUMBING
J 0
(-5575 1475);
DISPLAY 1.595745 (-5575 1475);
PAINT GREEN (-5575 1475);
DISPLAY INVISIBLE (-5575 1475);
FORCEPROP 2 LAST CDS_LIB mstr_standard
J 0
(-5575 1525);
PAINT MONO (-5575 1525);
DISPLAY INVISIBLE (-5575 1525);
FORCEADD TAP..6
(-5575 1625);
FORCEPROP 3 LASTPIN (-5525 1625) SIG_NAME M_F_DQ<2>
J 0
(-5515 1635);
DISPLAY 0.659574 (-5515 1635);
PAINT MONO (-5515 1635);
DISPLAY INVISIBLE (-5515 1635);
FORCEPROP 1 LASTPIN (-5525 1625) BN 2
J 0
(-5577 1633);
DISPLAY 0.617021 (-5577 1633);
PAINT PINK (-5577 1633);
FORCEPROP 1 LAST PATH I23
J 0
(-5577 1625);
DISPLAY 0.872340 (-5577 1625);
PAINT GREEN (-5577 1625);
DISPLAY INVISIBLE (-5577 1625);
FORCEPROP 1 LAST HDL_TAP TRUE
J 0
(-5250 1500);
DISPLAY 1.595745 (-5250 1500);
PAINT GREEN (-5250 1500);
DISPLAY INVISIBLE (-5250 1500);
FORCEPROP 1 LAST BODY_TYPE PLUMBING
J 0
(-5575 1575);
DISPLAY 1.595745 (-5575 1575);
PAINT GREEN (-5575 1575);
DISPLAY INVISIBLE (-5575 1575);
FORCEPROP 2 LAST CDS_LIB mstr_standard
J 0
(-5575 1625);
PAINT MONO (-5575 1625);
DISPLAY INVISIBLE (-5575 1625);
FORCEADD TAP..6
(-5575 1675);
FORCEPROP 3 LASTPIN (-5525 1675) SIG_NAME M_F_DQ<3>
J 0
(-5515 1685);
DISPLAY 0.659574 (-5515 1685);
PAINT MONO (-5515 1685);
DISPLAY INVISIBLE (-5515 1685);
FORCEPROP 1 LASTPIN (-5525 1675) BN 3
J 0
(-5577 1683);
DISPLAY 0.617021 (-5577 1683);
PAINT PINK (-5577 1683);
FORCEPROP 1 LAST PATH I24
J 0
(-5577 1675);
DISPLAY 0.872340 (-5577 1675);
PAINT GREEN (-5577 1675);
DISPLAY INVISIBLE (-5577 1675);
FORCEPROP 1 LAST HDL_TAP TRUE
J 0
(-5250 1550);
DISPLAY 1.595745 (-5250 1550);
PAINT GREEN (-5250 1550);
DISPLAY INVISIBLE (-5250 1550);
FORCEPROP 1 LAST BODY_TYPE PLUMBING
J 0
(-5575 1625);
DISPLAY 1.595745 (-5575 1625);
PAINT GREEN (-5575 1625);
DISPLAY INVISIBLE (-5575 1625);
FORCEPROP 2 LAST CDS_LIB mstr_standard
J 0
(-5575 1675);
PAINT MONO (-5575 1675);
DISPLAY INVISIBLE (-5575 1675);
FORCEADD TAP..6
(-5575 1725);
FORCEPROP 3 LASTPIN (-5525 1725) SIG_NAME M_F_DQ<4>
J 0
(-5515 1735);
DISPLAY 0.659574 (-5515 1735);
PAINT MONO (-5515 1735);
DISPLAY INVISIBLE (-5515 1735);
FORCEPROP 1 LASTPIN (-5525 1725) BN 4
J 0
(-5577 1733);
DISPLAY 0.617021 (-5577 1733);
PAINT PINK (-5577 1733);
FORCEPROP 1 LAST PATH I25
J 0
(-5577 1725);
DISPLAY 0.872340 (-5577 1725);
PAINT GREEN (-5577 1725);
DISPLAY INVISIBLE (-5577 1725);
FORCEPROP 1 LAST HDL_TAP TRUE
J 0
(-5250 1600);
DISPLAY 1.595745 (-5250 1600);
PAINT GREEN (-5250 1600);
DISPLAY INVISIBLE (-5250 1600);
FORCEPROP 1 LAST BODY_TYPE PLUMBING
J 0
(-5575 1675);
DISPLAY 1.595745 (-5575 1675);
PAINT GREEN (-5575 1675);
DISPLAY INVISIBLE (-5575 1675);
FORCEPROP 2 LAST CDS_LIB mstr_standard
J 0
(-5575 1725);
PAINT MONO (-5575 1725);
DISPLAY INVISIBLE (-5575 1725);
FORCEADD TAP..6
(-5575 1775);
FORCEPROP 3 LASTPIN (-5525 1775) SIG_NAME M_F_DQ<5>
J 0
(-5515 1785);
DISPLAY 0.659574 (-5515 1785);
PAINT MONO (-5515 1785);
DISPLAY INVISIBLE (-5515 1785);
FORCEPROP 1 LASTPIN (-5525 1775) BN 5
J 0
(-5577 1783);
DISPLAY 0.617021 (-5577 1783);
PAINT PINK (-5577 1783);
FORCEPROP 1 LAST PATH I26
J 0
(-5577 1775);
DISPLAY 0.872340 (-5577 1775);
PAINT GREEN (-5577 1775);
DISPLAY INVISIBLE (-5577 1775);
FORCEPROP 1 LAST HDL_TAP TRUE
J 0
(-5250 1650);
DISPLAY 1.595745 (-5250 1650);
PAINT GREEN (-5250 1650);
DISPLAY INVISIBLE (-5250 1650);
FORCEPROP 1 LAST BODY_TYPE PLUMBING
J 0
(-5575 1725);
DISPLAY 1.595745 (-5575 1725);
PAINT GREEN (-5575 1725);
DISPLAY INVISIBLE (-5575 1725);
FORCEPROP 2 LAST CDS_LIB mstr_standard
J 0
(-5575 1775);
PAINT MONO (-5575 1775);
DISPLAY INVISIBLE (-5575 1775);
FORCEADD TAP..6
(-5575 1825);
FORCEPROP 3 LASTPIN (-5525 1825) SIG_NAME M_F_DQ<6>
J 0
(-5515 1835);
DISPLAY 0.659574 (-5515 1835);
PAINT MONO (-5515 1835);
DISPLAY INVISIBLE (-5515 1835);
FORCEPROP 1 LASTPIN (-5525 1825) BN 6
J 0
(-5577 1833);
DISPLAY 0.617021 (-5577 1833);
PAINT PINK (-5577 1833);
FORCEPROP 1 LAST PATH I27
J 0
(-5577 1825);
DISPLAY 0.872340 (-5577 1825);
PAINT GREEN (-5577 1825);
DISPLAY INVISIBLE (-5577 1825);
FORCEPROP 1 LAST HDL_TAP TRUE
J 0
(-5250 1700);
DISPLAY 1.595745 (-5250 1700);
PAINT GREEN (-5250 1700);
DISPLAY INVISIBLE (-5250 1700);
FORCEPROP 1 LAST BODY_TYPE PLUMBING
J 0
(-5575 1775);
DISPLAY 1.595745 (-5575 1775);
PAINT GREEN (-5575 1775);
DISPLAY INVISIBLE (-5575 1775);
FORCEPROP 2 LAST CDS_LIB mstr_standard
J 0
(-5575 1825);
PAINT MONO (-5575 1825);
DISPLAY INVISIBLE (-5575 1825);
FORCEADD TAP..6
(-5575 1925);
FORCEPROP 3 LASTPIN (-5525 1925) SIG_NAME M_F_DQ<8>
J 0
(-5515 1935);
DISPLAY 0.659574 (-5515 1935);
PAINT MONO (-5515 1935);
DISPLAY INVISIBLE (-5515 1935);
FORCEPROP 1 LASTPIN (-5525 1925) BN 8
J 0
(-5577 1933);
DISPLAY 0.617021 (-5577 1933);
PAINT PINK (-5577 1933);
FORCEPROP 1 LAST PATH I28
J 0
(-5577 1925);
DISPLAY 0.872340 (-5577 1925);
PAINT GREEN (-5577 1925);
DISPLAY INVISIBLE (-5577 1925);
FORCEPROP 1 LAST HDL_TAP TRUE
J 0
(-5250 1800);
DISPLAY 1.595745 (-5250 1800);
PAINT GREEN (-5250 1800);
DISPLAY INVISIBLE (-5250 1800);
FORCEPROP 1 LAST BODY_TYPE PLUMBING
J 0
(-5575 1875);
DISPLAY 1.595745 (-5575 1875);
PAINT GREEN (-5575 1875);
DISPLAY INVISIBLE (-5575 1875);
FORCEPROP 2 LAST CDS_LIB mstr_standard
J 0
(-5575 1925);
PAINT MONO (-5575 1925);
DISPLAY INVISIBLE (-5575 1925);
FORCEADD TAP..6
(-5575 1875);
FORCEPROP 3 LASTPIN (-5525 1875) SIG_NAME M_F_DQ<7>
J 0
(-5515 1885);
DISPLAY 0.659574 (-5515 1885);
PAINT MONO (-5515 1885);
DISPLAY INVISIBLE (-5515 1885);
FORCEPROP 1 LASTPIN (-5525 1875) BN 7
J 0
(-5577 1883);
DISPLAY 0.617021 (-5577 1883);
PAINT PINK (-5577 1883);
FORCEPROP 1 LAST PATH I29
J 0
(-5577 1875);
DISPLAY 0.872340 (-5577 1875);
PAINT GREEN (-5577 1875);
DISPLAY INVISIBLE (-5577 1875);
FORCEPROP 1 LAST HDL_TAP TRUE
J 0
(-5250 1750);
DISPLAY 1.595745 (-5250 1750);
PAINT GREEN (-5250 1750);
DISPLAY INVISIBLE (-5250 1750);
FORCEPROP 1 LAST BODY_TYPE PLUMBING
J 0
(-5575 1825);
DISPLAY 1.595745 (-5575 1825);
PAINT GREEN (-5575 1825);
DISPLAY INVISIBLE (-5575 1825);
FORCEPROP 2 LAST CDS_LIB mstr_standard
J 0
(-5575 1875);
PAINT MONO (-5575 1875);
DISPLAY INVISIBLE (-5575 1875);
FORCEADD OFFPAGE..5
(-6425 1025);
FORCEPROP 2 LAST $XR1 54 
J 0
(-6769 1025);
DISPLAY 0.638298 (-6769 1025);
PAINT MONO (-6769 1025);
FORCEPROP 2 LAST $XR0 53 
J 0
(-6679 1025);
DISPLAY 0.638298 (-6679 1025);
PAINT MONO (-6679 1025);
FORCEPROP 2 LAST PATH I3
J 0
(-6375 1100);
DISPLAY 1.021277 (-6375 1100);
PAINT ORANGE (-6375 1100);
DISPLAY INVISIBLE (-6375 1100);
FORCEPROP 1 LAST COMMENT_BODY TRUE
J 0
(-6325 950);
DISPLAY 1.170213 (-6325 950);
PAINT GREEN (-6325 950);
DISPLAY INVISIBLE (-6325 950);
FORCEPROP 1 LAST OFFPAGE TRUE
J 0
(-6100 900);
DISPLAY 1.170213 (-6100 900);
PAINT GREEN (-6100 900);
DISPLAY INVISIBLE (-6100 900);
FORCEPROP 2 LAST CDS_LIB mstr_standard
J 0
(-6425 1025);
PAINT MONO (-6425 1025);
DISPLAY INVISIBLE (-6425 1025);
FORCEADD TAP..6
(-5575 1975);
FORCEPROP 3 LASTPIN (-5525 1975) SIG_NAME M_F_DQ<9>
J 0
(-5515 1985);
DISPLAY 0.659574 (-5515 1985);
PAINT MONO (-5515 1985);
DISPLAY INVISIBLE (-5515 1985);
FORCEPROP 1 LASTPIN (-5525 1975) BN 9
J 0
(-5577 1983);
DISPLAY 0.617021 (-5577 1983);
PAINT PINK (-5577 1983);
FORCEPROP 1 LAST PATH I30
J 0
(-5577 1975);
DISPLAY 0.872340 (-5577 1975);
PAINT GREEN (-5577 1975);
DISPLAY INVISIBLE (-5577 1975);
FORCEPROP 1 LAST HDL_TAP TRUE
J 0
(-5250 1850);
DISPLAY 1.595745 (-5250 1850);
PAINT GREEN (-5250 1850);
DISPLAY INVISIBLE (-5250 1850);
FORCEPROP 1 LAST BODY_TYPE PLUMBING
J 0
(-5575 1925);
DISPLAY 1.595745 (-5575 1925);
PAINT GREEN (-5575 1925);
DISPLAY INVISIBLE (-5575 1925);
FORCEPROP 2 LAST CDS_LIB mstr_standard
J 0
(-5575 1975);
PAINT MONO (-5575 1975);
DISPLAY INVISIBLE (-5575 1975);
FORCEADD TAP..6
(-5575 2025);
FORCEPROP 3 LASTPIN (-5525 2025) SIG_NAME M_F_DQ<10>
J 0
(-5515 2035);
DISPLAY 0.659574 (-5515 2035);
PAINT MONO (-5515 2035);
DISPLAY INVISIBLE (-5515 2035);
FORCEPROP 1 LASTPIN (-5525 2025) BN 10
J 0
(-5577 2033);
DISPLAY 0.617021 (-5577 2033);
PAINT PINK (-5577 2033);
FORCEPROP 1 LAST PATH I32
J 0
(-5577 2025);
DISPLAY 0.872340 (-5577 2025);
PAINT GREEN (-5577 2025);
DISPLAY INVISIBLE (-5577 2025);
FORCEPROP 1 LAST HDL_TAP TRUE
J 0
(-5250 1900);
DISPLAY 1.595745 (-5250 1900);
PAINT GREEN (-5250 1900);
DISPLAY INVISIBLE (-5250 1900);
FORCEPROP 1 LAST BODY_TYPE PLUMBING
J 0
(-5575 1975);
DISPLAY 1.595745 (-5575 1975);
PAINT GREEN (-5575 1975);
DISPLAY INVISIBLE (-5575 1975);
FORCEPROP 2 LAST CDS_LIB mstr_standard
J 0
(-5575 2025);
PAINT MONO (-5575 2025);
DISPLAY INVISIBLE (-5575 2025);
FORCEADD TAP..6
(-5575 2075);
FORCEPROP 3 LASTPIN (-5525 2075) SIG_NAME M_F_DQ<11>
J 0
(-5515 2085);
DISPLAY 0.659574 (-5515 2085);
PAINT MONO (-5515 2085);
DISPLAY INVISIBLE (-5515 2085);
FORCEPROP 1 LASTPIN (-5525 2075) BN 11
J 0
(-5577 2083);
DISPLAY 0.617021 (-5577 2083);
PAINT PINK (-5577 2083);
FORCEPROP 1 LAST PATH I33
J 0
(-5577 2075);
DISPLAY 0.872340 (-5577 2075);
PAINT GREEN (-5577 2075);
DISPLAY INVISIBLE (-5577 2075);
FORCEPROP 1 LAST HDL_TAP TRUE
J 0
(-5250 1950);
DISPLAY 1.595745 (-5250 1950);
PAINT GREEN (-5250 1950);
DISPLAY INVISIBLE (-5250 1950);
FORCEPROP 1 LAST BODY_TYPE PLUMBING
J 0
(-5575 2025);
DISPLAY 1.595745 (-5575 2025);
PAINT GREEN (-5575 2025);
DISPLAY INVISIBLE (-5575 2025);
FORCEPROP 2 LAST CDS_LIB mstr_standard
J 0
(-5575 2075);
PAINT MONO (-5575 2075);
DISPLAY INVISIBLE (-5575 2075);
FORCEADD TAP..6
(-5575 2125);
FORCEPROP 3 LASTPIN (-5525 2125) SIG_NAME M_F_DQ<12>
J 0
(-5515 2135);
DISPLAY 0.659574 (-5515 2135);
PAINT MONO (-5515 2135);
DISPLAY INVISIBLE (-5515 2135);
FORCEPROP 1 LASTPIN (-5525 2125) BN 12
J 0
(-5577 2133);
DISPLAY 0.617021 (-5577 2133);
PAINT PINK (-5577 2133);
FORCEPROP 1 LAST PATH I34
J 0
(-5577 2125);
DISPLAY 0.872340 (-5577 2125);
PAINT GREEN (-5577 2125);
DISPLAY INVISIBLE (-5577 2125);
FORCEPROP 1 LAST HDL_TAP TRUE
J 0
(-5250 2000);
DISPLAY 1.595745 (-5250 2000);
PAINT GREEN (-5250 2000);
DISPLAY INVISIBLE (-5250 2000);
FORCEPROP 1 LAST BODY_TYPE PLUMBING
J 0
(-5575 2075);
DISPLAY 1.595745 (-5575 2075);
PAINT GREEN (-5575 2075);
DISPLAY INVISIBLE (-5575 2075);
FORCEPROP 2 LAST CDS_LIB mstr_standard
J 0
(-5575 2125);
PAINT MONO (-5575 2125);
DISPLAY INVISIBLE (-5575 2125);
FORCEADD TAP..6
(-5575 2175);
FORCEPROP 3 LASTPIN (-5525 2175) SIG_NAME M_F_DQ<13>
J 0
(-5515 2185);
DISPLAY 0.659574 (-5515 2185);
PAINT MONO (-5515 2185);
DISPLAY INVISIBLE (-5515 2185);
FORCEPROP 1 LASTPIN (-5525 2175) BN 13
J 0
(-5577 2183);
DISPLAY 0.617021 (-5577 2183);
PAINT PINK (-5577 2183);
FORCEPROP 1 LAST PATH I35
J 0
(-5577 2175);
DISPLAY 0.872340 (-5577 2175);
PAINT GREEN (-5577 2175);
DISPLAY INVISIBLE (-5577 2175);
FORCEPROP 1 LAST HDL_TAP TRUE
J 0
(-5250 2050);
DISPLAY 1.595745 (-5250 2050);
PAINT GREEN (-5250 2050);
DISPLAY INVISIBLE (-5250 2050);
FORCEPROP 1 LAST BODY_TYPE PLUMBING
J 0
(-5575 2125);
DISPLAY 1.595745 (-5575 2125);
PAINT GREEN (-5575 2125);
DISPLAY INVISIBLE (-5575 2125);
FORCEPROP 2 LAST CDS_LIB mstr_standard
J 0
(-5575 2175);
PAINT MONO (-5575 2175);
DISPLAY INVISIBLE (-5575 2175);
FORCEADD TAP..6
(-5575 2225);
FORCEPROP 3 LASTPIN (-5525 2225) SIG_NAME M_F_DQ<14>
J 0
(-5515 2235);
DISPLAY 0.659574 (-5515 2235);
PAINT MONO (-5515 2235);
DISPLAY INVISIBLE (-5515 2235);
FORCEPROP 1 LASTPIN (-5525 2225) BN 14
J 0
(-5577 2233);
DISPLAY 0.617021 (-5577 2233);
PAINT PINK (-5577 2233);
FORCEPROP 1 LAST PATH I36
J 0
(-5577 2225);
DISPLAY 0.872340 (-5577 2225);
PAINT GREEN (-5577 2225);
DISPLAY INVISIBLE (-5577 2225);
FORCEPROP 1 LAST HDL_TAP TRUE
J 0
(-5250 2100);
DISPLAY 1.595745 (-5250 2100);
PAINT GREEN (-5250 2100);
DISPLAY INVISIBLE (-5250 2100);
FORCEPROP 1 LAST BODY_TYPE PLUMBING
J 0
(-5575 2175);
DISPLAY 1.595745 (-5575 2175);
PAINT GREEN (-5575 2175);
DISPLAY INVISIBLE (-5575 2175);
FORCEPROP 2 LAST CDS_LIB mstr_standard
J 0
(-5575 2225);
PAINT MONO (-5575 2225);
DISPLAY INVISIBLE (-5575 2225);
FORCEADD TAP..6
(-5575 2275);
FORCEPROP 3 LASTPIN (-5525 2275) SIG_NAME M_F_DQ<15>
J 0
(-5515 2285);
DISPLAY 0.659574 (-5515 2285);
PAINT MONO (-5515 2285);
DISPLAY INVISIBLE (-5515 2285);
FORCEPROP 1 LASTPIN (-5525 2275) BN 15
J 0
(-5577 2283);
DISPLAY 0.617021 (-5577 2283);
PAINT PINK (-5577 2283);
FORCEPROP 1 LAST PATH I37
J 0
(-5577 2275);
DISPLAY 0.872340 (-5577 2275);
PAINT GREEN (-5577 2275);
DISPLAY INVISIBLE (-5577 2275);
FORCEPROP 1 LAST HDL_TAP TRUE
J 0
(-5250 2150);
DISPLAY 1.595745 (-5250 2150);
PAINT GREEN (-5250 2150);
DISPLAY INVISIBLE (-5250 2150);
FORCEPROP 1 LAST BODY_TYPE PLUMBING
J 0
(-5575 2225);
DISPLAY 1.595745 (-5575 2225);
PAINT GREEN (-5575 2225);
DISPLAY INVISIBLE (-5575 2225);
FORCEPROP 2 LAST CDS_LIB mstr_standard
J 0
(-5575 2275);
PAINT MONO (-5575 2275);
DISPLAY INVISIBLE (-5575 2275);
FORCEADD TAP..6
(-5575 2325);
FORCEPROP 3 LASTPIN (-5525 2325) SIG_NAME M_F_DQ<16>
J 0
(-5515 2335);
DISPLAY 0.659574 (-5515 2335);
PAINT MONO (-5515 2335);
DISPLAY INVISIBLE (-5515 2335);
FORCEPROP 1 LASTPIN (-5525 2325) BN 16
J 0
(-5577 2333);
DISPLAY 0.617021 (-5577 2333);
PAINT PINK (-5577 2333);
FORCEPROP 1 LAST PATH I38
J 0
(-5577 2325);
DISPLAY 0.872340 (-5577 2325);
PAINT GREEN (-5577 2325);
DISPLAY INVISIBLE (-5577 2325);
FORCEPROP 1 LAST HDL_TAP TRUE
J 0
(-5250 2200);
DISPLAY 1.595745 (-5250 2200);
PAINT GREEN (-5250 2200);
DISPLAY INVISIBLE (-5250 2200);
FORCEPROP 1 LAST BODY_TYPE PLUMBING
J 0
(-5575 2275);
DISPLAY 1.595745 (-5575 2275);
PAINT GREEN (-5575 2275);
DISPLAY INVISIBLE (-5575 2275);
FORCEPROP 2 LAST CDS_LIB mstr_standard
J 0
(-5575 2325);
PAINT MONO (-5575 2325);
DISPLAY INVISIBLE (-5575 2325);
FORCEADD TAP..6
(-5575 2375);
FORCEPROP 3 LASTPIN (-5525 2375) SIG_NAME M_F_DQ<17>
J 0
(-5515 2385);
DISPLAY 0.659574 (-5515 2385);
PAINT MONO (-5515 2385);
DISPLAY INVISIBLE (-5515 2385);
FORCEPROP 1 LASTPIN (-5525 2375) BN 17
J 0
(-5577 2383);
DISPLAY 0.617021 (-5577 2383);
PAINT PINK (-5577 2383);
FORCEPROP 1 LAST PATH I39
J 0
(-5577 2375);
DISPLAY 0.872340 (-5577 2375);
PAINT GREEN (-5577 2375);
DISPLAY INVISIBLE (-5577 2375);
FORCEPROP 1 LAST HDL_TAP TRUE
J 0
(-5250 2250);
DISPLAY 1.595745 (-5250 2250);
PAINT GREEN (-5250 2250);
DISPLAY INVISIBLE (-5250 2250);
FORCEPROP 1 LAST BODY_TYPE PLUMBING
J 0
(-5575 2325);
DISPLAY 1.595745 (-5575 2325);
PAINT GREEN (-5575 2325);
DISPLAY INVISIBLE (-5575 2325);
FORCEPROP 2 LAST CDS_LIB mstr_standard
J 0
(-5575 2375);
PAINT MONO (-5575 2375);
DISPLAY INVISIBLE (-5575 2375);
FORCEADD OFFPAGE..6
(-6425 1475);
FORCEPROP 2 LAST $XR1 54 
J 0
(-6764 1475);
DISPLAY 0.638298 (-6764 1475);
PAINT MONO (-6764 1475);
FORCEPROP 2 LAST $XR0 53 
J 0
(-6674 1475);
DISPLAY 0.638298 (-6674 1475);
PAINT MONO (-6674 1475);
FORCEPROP 2 LAST PATH I4
J 0
(-6375 1550);
DISPLAY 1.021277 (-6375 1550);
PAINT ORANGE (-6375 1550);
DISPLAY INVISIBLE (-6375 1550);
FORCEPROP 1 LAST COMMENT_BODY TRUE
J 0
(-6325 1400);
DISPLAY 1.170213 (-6325 1400);
PAINT GREEN (-6325 1400);
DISPLAY INVISIBLE (-6325 1400);
FORCEPROP 1 LAST OFFPAGE TRUE
J 0
(-6100 1350);
DISPLAY 1.170213 (-6100 1350);
PAINT GREEN (-6100 1350);
DISPLAY INVISIBLE (-6100 1350);
FORCEPROP 2 LAST CDS_LIB mstr_standard
J 0
(-6425 1475);
PAINT MONO (-6425 1475);
DISPLAY INVISIBLE (-6425 1475);
FORCEADD TAP..6
(-5575 2425);
FORCEPROP 3 LASTPIN (-5525 2425) SIG_NAME M_F_DQ<18>
J 0
(-5515 2435);
DISPLAY 0.659574 (-5515 2435);
PAINT MONO (-5515 2435);
DISPLAY INVISIBLE (-5515 2435);
FORCEPROP 1 LASTPIN (-5525 2425) BN 18
J 0
(-5577 2433);
DISPLAY 0.617021 (-5577 2433);
PAINT PINK (-5577 2433);
FORCEPROP 1 LAST PATH I40
J 0
(-5577 2425);
DISPLAY 0.872340 (-5577 2425);
PAINT GREEN (-5577 2425);
DISPLAY INVISIBLE (-5577 2425);
FORCEPROP 1 LAST HDL_TAP TRUE
J 0
(-5250 2300);
DISPLAY 1.595745 (-5250 2300);
PAINT GREEN (-5250 2300);
DISPLAY INVISIBLE (-5250 2300);
FORCEPROP 1 LAST BODY_TYPE PLUMBING
J 0
(-5575 2375);
DISPLAY 1.595745 (-5575 2375);
PAINT GREEN (-5575 2375);
DISPLAY INVISIBLE (-5575 2375);
FORCEPROP 2 LAST CDS_LIB mstr_standard
J 0
(-5575 2425);
PAINT MONO (-5575 2425);
DISPLAY INVISIBLE (-5575 2425);
FORCEADD TAP..6
(-5575 2475);
FORCEPROP 3 LASTPIN (-5525 2475) SIG_NAME M_F_DQ<19>
J 0
(-5515 2485);
DISPLAY 0.659574 (-5515 2485);
PAINT MONO (-5515 2485);
DISPLAY INVISIBLE (-5515 2485);
FORCEPROP 1 LASTPIN (-5525 2475) BN 19
J 0
(-5577 2483);
DISPLAY 0.617021 (-5577 2483);
PAINT PINK (-5577 2483);
FORCEPROP 1 LAST PATH I41
J 0
(-5577 2475);
DISPLAY 0.872340 (-5577 2475);
PAINT GREEN (-5577 2475);
DISPLAY INVISIBLE (-5577 2475);
FORCEPROP 1 LAST HDL_TAP TRUE
J 0
(-5250 2350);
DISPLAY 1.595745 (-5250 2350);
PAINT GREEN (-5250 2350);
DISPLAY INVISIBLE (-5250 2350);
FORCEPROP 1 LAST BODY_TYPE PLUMBING
J 0
(-5575 2425);
DISPLAY 1.595745 (-5575 2425);
PAINT GREEN (-5575 2425);
DISPLAY INVISIBLE (-5575 2425);
FORCEPROP 2 LAST CDS_LIB mstr_standard
J 0
(-5575 2475);
PAINT MONO (-5575 2475);
DISPLAY INVISIBLE (-5575 2475);
FORCEADD TAP..6
(-5575 2525);
FORCEPROP 3 LASTPIN (-5525 2525) SIG_NAME M_F_DQ<20>
J 0
(-5515 2535);
DISPLAY 0.659574 (-5515 2535);
PAINT MONO (-5515 2535);
DISPLAY INVISIBLE (-5515 2535);
FORCEPROP 1 LASTPIN (-5525 2525) BN 20
J 0
(-5577 2533);
DISPLAY 0.617021 (-5577 2533);
PAINT PINK (-5577 2533);
FORCEPROP 1 LAST PATH I42
J 0
(-5577 2525);
DISPLAY 0.872340 (-5577 2525);
PAINT GREEN (-5577 2525);
DISPLAY INVISIBLE (-5577 2525);
FORCEPROP 1 LAST HDL_TAP TRUE
J 0
(-5250 2400);
DISPLAY 1.595745 (-5250 2400);
PAINT GREEN (-5250 2400);
DISPLAY INVISIBLE (-5250 2400);
FORCEPROP 1 LAST BODY_TYPE PLUMBING
J 0
(-5575 2475);
DISPLAY 1.595745 (-5575 2475);
PAINT GREEN (-5575 2475);
DISPLAY INVISIBLE (-5575 2475);
FORCEPROP 2 LAST CDS_LIB mstr_standard
J 0
(-5575 2525);
PAINT MONO (-5575 2525);
DISPLAY INVISIBLE (-5575 2525);
FORCEADD TAP..6
(-5575 2575);
FORCEPROP 3 LASTPIN (-5525 2575) SIG_NAME M_F_DQ<21>
J 0
(-5515 2585);
DISPLAY 0.659574 (-5515 2585);
PAINT MONO (-5515 2585);
DISPLAY INVISIBLE (-5515 2585);
FORCEPROP 1 LASTPIN (-5525 2575) BN 21
J 0
(-5577 2583);
DISPLAY 0.617021 (-5577 2583);
PAINT PINK (-5577 2583);
FORCEPROP 1 LAST PATH I43
J 0
(-5577 2575);
DISPLAY 0.872340 (-5577 2575);
PAINT GREEN (-5577 2575);
DISPLAY INVISIBLE (-5577 2575);
FORCEPROP 1 LAST HDL_TAP TRUE
J 0
(-5250 2450);
DISPLAY 1.595745 (-5250 2450);
PAINT GREEN (-5250 2450);
DISPLAY INVISIBLE (-5250 2450);
FORCEPROP 1 LAST BODY_TYPE PLUMBING
J 0
(-5575 2525);
DISPLAY 1.595745 (-5575 2525);
PAINT GREEN (-5575 2525);
DISPLAY INVISIBLE (-5575 2525);
FORCEPROP 2 LAST CDS_LIB mstr_standard
J 0
(-5575 2575);
PAINT MONO (-5575 2575);
DISPLAY INVISIBLE (-5575 2575);
FORCEADD TAP..6
(-5575 2625);
FORCEPROP 3 LASTPIN (-5525 2625) SIG_NAME M_F_DQ<22>
J 0
(-5515 2635);
DISPLAY 0.659574 (-5515 2635);
PAINT MONO (-5515 2635);
DISPLAY INVISIBLE (-5515 2635);
FORCEPROP 1 LASTPIN (-5525 2625) BN 22
J 0
(-5577 2633);
DISPLAY 0.617021 (-5577 2633);
PAINT PINK (-5577 2633);
FORCEPROP 1 LAST PATH I44
J 0
(-5577 2625);
DISPLAY 0.872340 (-5577 2625);
PAINT GREEN (-5577 2625);
DISPLAY INVISIBLE (-5577 2625);
FORCEPROP 1 LAST HDL_TAP TRUE
J 0
(-5250 2500);
DISPLAY 1.595745 (-5250 2500);
PAINT GREEN (-5250 2500);
DISPLAY INVISIBLE (-5250 2500);
FORCEPROP 1 LAST BODY_TYPE PLUMBING
J 0
(-5575 2575);
DISPLAY 1.595745 (-5575 2575);
PAINT GREEN (-5575 2575);
DISPLAY INVISIBLE (-5575 2575);
FORCEPROP 2 LAST CDS_LIB mstr_standard
J 0
(-5575 2625);
PAINT MONO (-5575 2625);
DISPLAY INVISIBLE (-5575 2625);
FORCEADD TAP..6
(-5575 2675);
FORCEPROP 3 LASTPIN (-5525 2675) SIG_NAME M_F_DQ<23>
J 0
(-5515 2685);
DISPLAY 0.659574 (-5515 2685);
PAINT MONO (-5515 2685);
DISPLAY INVISIBLE (-5515 2685);
FORCEPROP 1 LASTPIN (-5525 2675) BN 23
J 0
(-5577 2683);
DISPLAY 0.617021 (-5577 2683);
PAINT PINK (-5577 2683);
FORCEPROP 1 LAST PATH I45
J 0
(-5577 2675);
DISPLAY 0.872340 (-5577 2675);
PAINT GREEN (-5577 2675);
DISPLAY INVISIBLE (-5577 2675);
FORCEPROP 1 LAST HDL_TAP TRUE
J 0
(-5250 2550);
DISPLAY 1.595745 (-5250 2550);
PAINT GREEN (-5250 2550);
DISPLAY INVISIBLE (-5250 2550);
FORCEPROP 1 LAST BODY_TYPE PLUMBING
J 0
(-5575 2625);
DISPLAY 1.595745 (-5575 2625);
PAINT GREEN (-5575 2625);
DISPLAY INVISIBLE (-5575 2625);
FORCEPROP 2 LAST CDS_LIB mstr_standard
J 0
(-5575 2675);
PAINT MONO (-5575 2675);
DISPLAY INVISIBLE (-5575 2675);
FORCEADD TAP..6
(-5575 2725);
FORCEPROP 3 LASTPIN (-5525 2725) SIG_NAME M_F_DQ<24>
J 0
(-5515 2735);
DISPLAY 0.659574 (-5515 2735);
PAINT MONO (-5515 2735);
DISPLAY INVISIBLE (-5515 2735);
FORCEPROP 1 LASTPIN (-5525 2725) BN 24
J 0
(-5577 2733);
DISPLAY 0.617021 (-5577 2733);
PAINT PINK (-5577 2733);
FORCEPROP 1 LAST PATH I46
J 0
(-5577 2725);
DISPLAY 0.872340 (-5577 2725);
PAINT GREEN (-5577 2725);
DISPLAY INVISIBLE (-5577 2725);
FORCEPROP 1 LAST HDL_TAP TRUE
J 0
(-5250 2600);
DISPLAY 1.595745 (-5250 2600);
PAINT GREEN (-5250 2600);
DISPLAY INVISIBLE (-5250 2600);
FORCEPROP 1 LAST BODY_TYPE PLUMBING
J 0
(-5575 2675);
DISPLAY 1.595745 (-5575 2675);
PAINT GREEN (-5575 2675);
DISPLAY INVISIBLE (-5575 2675);
FORCEPROP 2 LAST CDS_LIB mstr_standard
J 0
(-5575 2725);
PAINT MONO (-5575 2725);
DISPLAY INVISIBLE (-5575 2725);
FORCEADD TAP..6
(-5575 2825);
FORCEPROP 3 LASTPIN (-5525 2825) SIG_NAME M_F_DQ<26>
J 0
(-5515 2835);
DISPLAY 0.659574 (-5515 2835);
PAINT MONO (-5515 2835);
DISPLAY INVISIBLE (-5515 2835);
FORCEPROP 1 LASTPIN (-5525 2825) BN 26
J 0
(-5577 2833);
DISPLAY 0.617021 (-5577 2833);
PAINT PINK (-5577 2833);
FORCEPROP 1 LAST PATH I47
J 0
(-5577 2825);
DISPLAY 0.872340 (-5577 2825);
PAINT GREEN (-5577 2825);
DISPLAY INVISIBLE (-5577 2825);
FORCEPROP 1 LAST HDL_TAP TRUE
J 0
(-5250 2700);
DISPLAY 1.595745 (-5250 2700);
PAINT GREEN (-5250 2700);
DISPLAY INVISIBLE (-5250 2700);
FORCEPROP 1 LAST BODY_TYPE PLUMBING
J 0
(-5575 2775);
DISPLAY 1.595745 (-5575 2775);
PAINT GREEN (-5575 2775);
DISPLAY INVISIBLE (-5575 2775);
FORCEPROP 2 LAST CDS_LIB mstr_standard
J 0
(-5575 2825);
PAINT MONO (-5575 2825);
DISPLAY INVISIBLE (-5575 2825);
FORCEADD TAP..6
(-5575 2775);
FORCEPROP 3 LASTPIN (-5525 2775) SIG_NAME M_F_DQ<25>
J 0
(-5515 2785);
DISPLAY 0.659574 (-5515 2785);
PAINT MONO (-5515 2785);
DISPLAY INVISIBLE (-5515 2785);
FORCEPROP 1 LASTPIN (-5525 2775) BN 25
J 0
(-5577 2783);
DISPLAY 0.617021 (-5577 2783);
PAINT PINK (-5577 2783);
FORCEPROP 1 LAST PATH I48
J 0
(-5577 2775);
DISPLAY 0.872340 (-5577 2775);
PAINT GREEN (-5577 2775);
DISPLAY INVISIBLE (-5577 2775);
FORCEPROP 1 LAST HDL_TAP TRUE
J 0
(-5250 2650);
DISPLAY 1.595745 (-5250 2650);
PAINT GREEN (-5250 2650);
DISPLAY INVISIBLE (-5250 2650);
FORCEPROP 1 LAST BODY_TYPE PLUMBING
J 0
(-5575 2725);
DISPLAY 1.595745 (-5575 2725);
PAINT GREEN (-5575 2725);
DISPLAY INVISIBLE (-5575 2725);
FORCEPROP 2 LAST CDS_LIB mstr_standard
J 0
(-5575 2775);
PAINT MONO (-5575 2775);
DISPLAY INVISIBLE (-5575 2775);
FORCEADD TAP..6
(-5575 2875);
FORCEPROP 3 LASTPIN (-5525 2875) SIG_NAME M_F_DQ<27>
J 0
(-5515 2885);
DISPLAY 0.659574 (-5515 2885);
PAINT MONO (-5515 2885);
DISPLAY INVISIBLE (-5515 2885);
FORCEPROP 1 LASTPIN (-5525 2875) BN 27
J 0
(-5577 2883);
DISPLAY 0.617021 (-5577 2883);
PAINT PINK (-5577 2883);
FORCEPROP 1 LAST PATH I49
J 0
(-5577 2875);
DISPLAY 0.872340 (-5577 2875);
PAINT GREEN (-5577 2875);
DISPLAY INVISIBLE (-5577 2875);
FORCEPROP 1 LAST HDL_TAP TRUE
J 0
(-5250 2750);
DISPLAY 1.595745 (-5250 2750);
PAINT GREEN (-5250 2750);
DISPLAY INVISIBLE (-5250 2750);
FORCEPROP 1 LAST BODY_TYPE PLUMBING
J 0
(-5575 2825);
DISPLAY 1.595745 (-5575 2825);
PAINT GREEN (-5575 2825);
DISPLAY INVISIBLE (-5575 2825);
FORCEPROP 2 LAST CDS_LIB mstr_standard
J 0
(-5575 2875);
PAINT MONO (-5575 2875);
DISPLAY INVISIBLE (-5575 2875);
FORCEADD TAP..6
(-5575 625);
FORCEPROP 3 LASTPIN (-5525 625) SIG_NAME M_F_CLK_DN<0>
J 0
(-5515 635);
DISPLAY 0.659574 (-5515 635);
PAINT MONO (-5515 635);
DISPLAY INVISIBLE (-5515 635);
FORCEPROP 1 LASTPIN (-5525 625) BN 0
J 0
(-5577 633);
DISPLAY 0.617021 (-5577 633);
PAINT PINK (-5577 633);
FORCEPROP 1 LAST PATH I5
J 0
(-5577 625);
DISPLAY 0.872340 (-5577 625);
PAINT GREEN (-5577 625);
DISPLAY INVISIBLE (-5577 625);
FORCEPROP 1 LAST HDL_TAP TRUE
J 0
(-5250 500);
DISPLAY 1.595745 (-5250 500);
PAINT GREEN (-5250 500);
DISPLAY INVISIBLE (-5250 500);
FORCEPROP 1 LAST BODY_TYPE PLUMBING
J 0
(-5575 575);
DISPLAY 1.595745 (-5575 575);
PAINT GREEN (-5575 575);
DISPLAY INVISIBLE (-5575 575);
FORCEPROP 2 LAST CDS_LIB mstr_standard
J 0
(-5575 625);
PAINT MONO (-5575 625);
DISPLAY INVISIBLE (-5575 625);
FORCEADD TAP..6
(-5575 2925);
FORCEPROP 3 LASTPIN (-5525 2925) SIG_NAME M_F_DQ<28>
J 0
(-5515 2935);
DISPLAY 0.659574 (-5515 2935);
PAINT MONO (-5515 2935);
DISPLAY INVISIBLE (-5515 2935);
FORCEPROP 1 LASTPIN (-5525 2925) BN 28
J 0
(-5577 2933);
DISPLAY 0.617021 (-5577 2933);
PAINT PINK (-5577 2933);
FORCEPROP 1 LAST PATH I50
J 0
(-5577 2925);
DISPLAY 0.872340 (-5577 2925);
PAINT GREEN (-5577 2925);
DISPLAY INVISIBLE (-5577 2925);
FORCEPROP 1 LAST HDL_TAP TRUE
J 0
(-5250 2800);
DISPLAY 1.595745 (-5250 2800);
PAINT GREEN (-5250 2800);
DISPLAY INVISIBLE (-5250 2800);
FORCEPROP 1 LAST BODY_TYPE PLUMBING
J 0
(-5575 2875);
DISPLAY 1.595745 (-5575 2875);
PAINT GREEN (-5575 2875);
DISPLAY INVISIBLE (-5575 2875);
FORCEPROP 2 LAST CDS_LIB mstr_standard
J 0
(-5575 2925);
PAINT MONO (-5575 2925);
DISPLAY INVISIBLE (-5575 2925);
FORCEADD TAP..6
(-5575 2975);
FORCEPROP 3 LASTPIN (-5525 2975) SIG_NAME M_F_DQ<29>
J 0
(-5515 2985);
DISPLAY 0.659574 (-5515 2985);
PAINT MONO (-5515 2985);
DISPLAY INVISIBLE (-5515 2985);
FORCEPROP 1 LASTPIN (-5525 2975) BN 29
J 0
(-5577 2983);
DISPLAY 0.617021 (-5577 2983);
PAINT PINK (-5577 2983);
FORCEPROP 1 LAST PATH I51
J 0
(-5577 2975);
DISPLAY 0.872340 (-5577 2975);
PAINT GREEN (-5577 2975);
DISPLAY INVISIBLE (-5577 2975);
FORCEPROP 1 LAST HDL_TAP TRUE
J 0
(-5250 2850);
DISPLAY 1.595745 (-5250 2850);
PAINT GREEN (-5250 2850);
DISPLAY INVISIBLE (-5250 2850);
FORCEPROP 1 LAST BODY_TYPE PLUMBING
J 0
(-5575 2925);
DISPLAY 1.595745 (-5575 2925);
PAINT GREEN (-5575 2925);
DISPLAY INVISIBLE (-5575 2925);
FORCEPROP 2 LAST CDS_LIB mstr_standard
J 0
(-5575 2975);
PAINT MONO (-5575 2975);
DISPLAY INVISIBLE (-5575 2975);
FORCEADD TAP..6
(-5575 3075);
FORCEPROP 3 LASTPIN (-5525 3075) SIG_NAME M_F_DQ<31>
J 0
(-5515 3085);
DISPLAY 0.659574 (-5515 3085);
PAINT MONO (-5515 3085);
DISPLAY INVISIBLE (-5515 3085);
FORCEPROP 1 LASTPIN (-5525 3075) BN 31
J 0
(-5577 3083);
DISPLAY 0.617021 (-5577 3083);
PAINT PINK (-5577 3083);
FORCEPROP 1 LAST PATH I52
J 0
(-5577 3075);
DISPLAY 0.872340 (-5577 3075);
PAINT GREEN (-5577 3075);
DISPLAY INVISIBLE (-5577 3075);
FORCEPROP 1 LAST HDL_TAP TRUE
J 0
(-5250 2950);
DISPLAY 1.595745 (-5250 2950);
PAINT GREEN (-5250 2950);
DISPLAY INVISIBLE (-5250 2950);
FORCEPROP 1 LAST BODY_TYPE PLUMBING
J 0
(-5575 3025);
DISPLAY 1.595745 (-5575 3025);
PAINT GREEN (-5575 3025);
DISPLAY INVISIBLE (-5575 3025);
FORCEPROP 2 LAST CDS_LIB mstr_standard
J 0
(-5575 3075);
PAINT MONO (-5575 3075);
DISPLAY INVISIBLE (-5575 3075);
FORCEADD TAP..6
(-5575 3025);
FORCEPROP 3 LASTPIN (-5525 3025) SIG_NAME M_F_DQ<30>
J 0
(-5515 3035);
DISPLAY 0.659574 (-5515 3035);
PAINT MONO (-5515 3035);
DISPLAY INVISIBLE (-5515 3035);
FORCEPROP 1 LASTPIN (-5525 3025) BN 30
J 0
(-5577 3033);
DISPLAY 0.617021 (-5577 3033);
PAINT PINK (-5577 3033);
FORCEPROP 1 LAST PATH I53
J 0
(-5577 3025);
DISPLAY 0.872340 (-5577 3025);
PAINT GREEN (-5577 3025);
DISPLAY INVISIBLE (-5577 3025);
FORCEPROP 1 LAST HDL_TAP TRUE
J 0
(-5250 2900);
DISPLAY 1.595745 (-5250 2900);
PAINT GREEN (-5250 2900);
DISPLAY INVISIBLE (-5250 2900);
FORCEPROP 1 LAST BODY_TYPE PLUMBING
J 0
(-5575 2975);
DISPLAY 1.595745 (-5575 2975);
PAINT GREEN (-5575 2975);
DISPLAY INVISIBLE (-5575 2975);
FORCEPROP 2 LAST CDS_LIB mstr_standard
J 0
(-5575 3025);
PAINT MONO (-5575 3025);
DISPLAY INVISIBLE (-5575 3025);
FORCEADD TAP..6
(-5575 3125);
FORCEPROP 3 LASTPIN (-5525 3125) SIG_NAME M_F_DQ<32>
J 0
(-5515 3135);
DISPLAY 0.659574 (-5515 3135);
PAINT MONO (-5515 3135);
DISPLAY INVISIBLE (-5515 3135);
FORCEPROP 1 LASTPIN (-5525 3125) BN 32
J 0
(-5577 3133);
DISPLAY 0.617021 (-5577 3133);
PAINT PINK (-5577 3133);
FORCEPROP 1 LAST PATH I54
J 0
(-5577 3125);
DISPLAY 0.872340 (-5577 3125);
PAINT GREEN (-5577 3125);
DISPLAY INVISIBLE (-5577 3125);
FORCEPROP 1 LAST HDL_TAP TRUE
J 0
(-5250 3000);
DISPLAY 1.595745 (-5250 3000);
PAINT GREEN (-5250 3000);
DISPLAY INVISIBLE (-5250 3000);
FORCEPROP 1 LAST BODY_TYPE PLUMBING
J 0
(-5575 3075);
DISPLAY 1.595745 (-5575 3075);
PAINT GREEN (-5575 3075);
DISPLAY INVISIBLE (-5575 3075);
FORCEPROP 2 LAST CDS_LIB mstr_standard
J 0
(-5575 3125);
PAINT MONO (-5575 3125);
DISPLAY INVISIBLE (-5575 3125);
FORCEADD TAP..6
(-5575 3175);
FORCEPROP 3 LASTPIN (-5525 3175) SIG_NAME M_F_DQ<33>
J 0
(-5515 3185);
DISPLAY 0.659574 (-5515 3185);
PAINT MONO (-5515 3185);
DISPLAY INVISIBLE (-5515 3185);
FORCEPROP 1 LASTPIN (-5525 3175) BN 33
J 0
(-5577 3183);
DISPLAY 0.617021 (-5577 3183);
PAINT PINK (-5577 3183);
FORCEPROP 1 LAST PATH I55
J 0
(-5577 3175);
DISPLAY 0.872340 (-5577 3175);
PAINT GREEN (-5577 3175);
DISPLAY INVISIBLE (-5577 3175);
FORCEPROP 1 LAST HDL_TAP TRUE
J 0
(-5250 3050);
DISPLAY 1.595745 (-5250 3050);
PAINT GREEN (-5250 3050);
DISPLAY INVISIBLE (-5250 3050);
FORCEPROP 1 LAST BODY_TYPE PLUMBING
J 0
(-5575 3125);
DISPLAY 1.595745 (-5575 3125);
PAINT GREEN (-5575 3125);
DISPLAY INVISIBLE (-5575 3125);
FORCEPROP 2 LAST CDS_LIB mstr_standard
J 0
(-5575 3175);
PAINT MONO (-5575 3175);
DISPLAY INVISIBLE (-5575 3175);
FORCEADD TAP..6
(-5575 3225);
FORCEPROP 3 LASTPIN (-5525 3225) SIG_NAME M_F_DQ<34>
J 0
(-5515 3235);
DISPLAY 0.659574 (-5515 3235);
PAINT MONO (-5515 3235);
DISPLAY INVISIBLE (-5515 3235);
FORCEPROP 1 LASTPIN (-5525 3225) BN 34
J 0
(-5577 3233);
DISPLAY 0.617021 (-5577 3233);
PAINT PINK (-5577 3233);
FORCEPROP 1 LAST PATH I56
J 0
(-5577 3225);
DISPLAY 0.872340 (-5577 3225);
PAINT GREEN (-5577 3225);
DISPLAY INVISIBLE (-5577 3225);
FORCEPROP 1 LAST HDL_TAP TRUE
J 0
(-5250 3100);
DISPLAY 1.595745 (-5250 3100);
PAINT GREEN (-5250 3100);
DISPLAY INVISIBLE (-5250 3100);
FORCEPROP 1 LAST BODY_TYPE PLUMBING
J 0
(-5575 3175);
DISPLAY 1.595745 (-5575 3175);
PAINT GREEN (-5575 3175);
DISPLAY INVISIBLE (-5575 3175);
FORCEPROP 2 LAST CDS_LIB mstr_standard
J 0
(-5575 3225);
PAINT MONO (-5575 3225);
DISPLAY INVISIBLE (-5575 3225);
FORCEADD TAP..6
(-5575 3275);
FORCEPROP 3 LASTPIN (-5525 3275) SIG_NAME M_F_DQ<35>
J 0
(-5515 3285);
DISPLAY 0.659574 (-5515 3285);
PAINT MONO (-5515 3285);
DISPLAY INVISIBLE (-5515 3285);
FORCEPROP 1 LASTPIN (-5525 3275) BN 35
J 0
(-5577 3283);
DISPLAY 0.617021 (-5577 3283);
PAINT PINK (-5577 3283);
FORCEPROP 1 LAST PATH I57
J 0
(-5577 3275);
DISPLAY 0.872340 (-5577 3275);
PAINT GREEN (-5577 3275);
DISPLAY INVISIBLE (-5577 3275);
FORCEPROP 1 LAST HDL_TAP TRUE
J 0
(-5250 3150);
DISPLAY 1.595745 (-5250 3150);
PAINT GREEN (-5250 3150);
DISPLAY INVISIBLE (-5250 3150);
FORCEPROP 1 LAST BODY_TYPE PLUMBING
J 0
(-5575 3225);
DISPLAY 1.595745 (-5575 3225);
PAINT GREEN (-5575 3225);
DISPLAY INVISIBLE (-5575 3225);
FORCEPROP 2 LAST CDS_LIB mstr_standard
J 0
(-5575 3275);
PAINT MONO (-5575 3275);
DISPLAY INVISIBLE (-5575 3275);
FORCEADD TAP..6
(-5575 3325);
FORCEPROP 3 LASTPIN (-5525 3325) SIG_NAME M_F_DQ<36>
J 0
(-5515 3335);
DISPLAY 0.659574 (-5515 3335);
PAINT MONO (-5515 3335);
DISPLAY INVISIBLE (-5515 3335);
FORCEPROP 1 LASTPIN (-5525 3325) BN 36
J 0
(-5577 3333);
DISPLAY 0.617021 (-5577 3333);
PAINT PINK (-5577 3333);
FORCEPROP 1 LAST PATH I58
J 0
(-5577 3325);
DISPLAY 0.872340 (-5577 3325);
PAINT GREEN (-5577 3325);
DISPLAY INVISIBLE (-5577 3325);
FORCEPROP 1 LAST HDL_TAP TRUE
J 0
(-5250 3200);
DISPLAY 1.595745 (-5250 3200);
PAINT GREEN (-5250 3200);
DISPLAY INVISIBLE (-5250 3200);
FORCEPROP 1 LAST BODY_TYPE PLUMBING
J 0
(-5575 3275);
DISPLAY 1.595745 (-5575 3275);
PAINT GREEN (-5575 3275);
DISPLAY INVISIBLE (-5575 3275);
FORCEPROP 2 LAST CDS_LIB mstr_standard
J 0
(-5575 3325);
PAINT MONO (-5575 3325);
DISPLAY INVISIBLE (-5575 3325);
FORCEADD TAP..6
(-5575 3375);
FORCEPROP 3 LASTPIN (-5525 3375) SIG_NAME M_F_DQ<37>
J 0
(-5515 3385);
DISPLAY 0.659574 (-5515 3385);
PAINT MONO (-5515 3385);
DISPLAY INVISIBLE (-5515 3385);
FORCEPROP 1 LASTPIN (-5525 3375) BN 37
J 0
(-5577 3383);
DISPLAY 0.617021 (-5577 3383);
PAINT PINK (-5577 3383);
FORCEPROP 1 LAST PATH I59
J 0
(-5577 3375);
DISPLAY 0.872340 (-5577 3375);
PAINT GREEN (-5577 3375);
DISPLAY INVISIBLE (-5577 3375);
FORCEPROP 1 LAST HDL_TAP TRUE
J 0
(-5250 3250);
DISPLAY 1.595745 (-5250 3250);
PAINT GREEN (-5250 3250);
DISPLAY INVISIBLE (-5250 3250);
FORCEPROP 1 LAST BODY_TYPE PLUMBING
J 0
(-5575 3325);
DISPLAY 1.595745 (-5575 3325);
PAINT GREEN (-5575 3325);
DISPLAY INVISIBLE (-5575 3325);
FORCEPROP 2 LAST CDS_LIB mstr_standard
J 0
(-5575 3375);
PAINT MONO (-5575 3375);
DISPLAY INVISIBLE (-5575 3375);
FORCEADD TAP..6
(-5575 675);
FORCEPROP 3 LASTPIN (-5525 675) SIG_NAME M_F_CLK_DN<1>
J 0
(-5515 685);
DISPLAY 0.659574 (-5515 685);
PAINT MONO (-5515 685);
DISPLAY INVISIBLE (-5515 685);
FORCEPROP 1 LASTPIN (-5525 675) BN 1
J 0
(-5577 683);
DISPLAY 0.617021 (-5577 683);
PAINT PINK (-5577 683);
FORCEPROP 1 LAST PATH I6
J 0
(-5577 675);
DISPLAY 0.872340 (-5577 675);
PAINT GREEN (-5577 675);
DISPLAY INVISIBLE (-5577 675);
FORCEPROP 1 LAST HDL_TAP TRUE
J 0
(-5250 550);
DISPLAY 1.595745 (-5250 550);
PAINT GREEN (-5250 550);
DISPLAY INVISIBLE (-5250 550);
FORCEPROP 1 LAST BODY_TYPE PLUMBING
J 0
(-5575 625);
DISPLAY 1.595745 (-5575 625);
PAINT GREEN (-5575 625);
DISPLAY INVISIBLE (-5575 625);
FORCEPROP 2 LAST CDS_LIB mstr_standard
J 0
(-5575 675);
PAINT MONO (-5575 675);
DISPLAY INVISIBLE (-5575 675);
FORCEADD TAP..6
(-5575 3425);
FORCEPROP 3 LASTPIN (-5525 3425) SIG_NAME M_F_DQ<38>
J 0
(-5515 3435);
DISPLAY 0.659574 (-5515 3435);
PAINT MONO (-5515 3435);
DISPLAY INVISIBLE (-5515 3435);
FORCEPROP 1 LASTPIN (-5525 3425) BN 38
J 0
(-5577 3433);
DISPLAY 0.617021 (-5577 3433);
PAINT PINK (-5577 3433);
FORCEPROP 1 LAST PATH I60
J 0
(-5577 3425);
DISPLAY 0.872340 (-5577 3425);
PAINT GREEN (-5577 3425);
DISPLAY INVISIBLE (-5577 3425);
FORCEPROP 1 LAST HDL_TAP TRUE
J 0
(-5250 3300);
DISPLAY 1.595745 (-5250 3300);
PAINT GREEN (-5250 3300);
DISPLAY INVISIBLE (-5250 3300);
FORCEPROP 1 LAST BODY_TYPE PLUMBING
J 0
(-5575 3375);
DISPLAY 1.595745 (-5575 3375);
PAINT GREEN (-5575 3375);
DISPLAY INVISIBLE (-5575 3375);
FORCEPROP 2 LAST CDS_LIB mstr_standard
J 0
(-5575 3425);
PAINT MONO (-5575 3425);
DISPLAY INVISIBLE (-5575 3425);
FORCEADD TAP..6
(-5575 3475);
FORCEPROP 3 LASTPIN (-5525 3475) SIG_NAME M_F_DQ<39>
J 0
(-5515 3485);
DISPLAY 0.659574 (-5515 3485);
PAINT MONO (-5515 3485);
DISPLAY INVISIBLE (-5515 3485);
FORCEPROP 1 LASTPIN (-5525 3475) BN 39
J 0
(-5577 3483);
DISPLAY 0.617021 (-5577 3483);
PAINT PINK (-5577 3483);
FORCEPROP 1 LAST PATH I61
J 0
(-5577 3475);
DISPLAY 0.872340 (-5577 3475);
PAINT GREEN (-5577 3475);
DISPLAY INVISIBLE (-5577 3475);
FORCEPROP 1 LAST HDL_TAP TRUE
J 0
(-5250 3350);
DISPLAY 1.595745 (-5250 3350);
PAINT GREEN (-5250 3350);
DISPLAY INVISIBLE (-5250 3350);
FORCEPROP 1 LAST BODY_TYPE PLUMBING
J 0
(-5575 3425);
DISPLAY 1.595745 (-5575 3425);
PAINT GREEN (-5575 3425);
DISPLAY INVISIBLE (-5575 3425);
FORCEPROP 2 LAST CDS_LIB mstr_standard
J 0
(-5575 3475);
PAINT MONO (-5575 3475);
DISPLAY INVISIBLE (-5575 3475);
FORCEADD TAP..6
(-5575 3525);
FORCEPROP 3 LASTPIN (-5525 3525) SIG_NAME M_F_DQ<40>
J 0
(-5515 3535);
DISPLAY 0.659574 (-5515 3535);
PAINT MONO (-5515 3535);
DISPLAY INVISIBLE (-5515 3535);
FORCEPROP 1 LASTPIN (-5525 3525) BN 40
J 0
(-5577 3533);
DISPLAY 0.617021 (-5577 3533);
PAINT PINK (-5577 3533);
FORCEPROP 1 LAST PATH I62
J 0
(-5577 3525);
DISPLAY 0.872340 (-5577 3525);
PAINT GREEN (-5577 3525);
DISPLAY INVISIBLE (-5577 3525);
FORCEPROP 1 LAST HDL_TAP TRUE
J 0
(-5250 3400);
DISPLAY 1.595745 (-5250 3400);
PAINT GREEN (-5250 3400);
DISPLAY INVISIBLE (-5250 3400);
FORCEPROP 1 LAST BODY_TYPE PLUMBING
J 0
(-5575 3475);
DISPLAY 1.595745 (-5575 3475);
PAINT GREEN (-5575 3475);
DISPLAY INVISIBLE (-5575 3475);
FORCEPROP 2 LAST CDS_LIB mstr_standard
J 0
(-5575 3525);
PAINT MONO (-5575 3525);
DISPLAY INVISIBLE (-5575 3525);
FORCEADD TAP..6
(-5575 3575);
FORCEPROP 3 LASTPIN (-5525 3575) SIG_NAME M_F_DQ<41>
J 0
(-5515 3585);
DISPLAY 0.659574 (-5515 3585);
PAINT MONO (-5515 3585);
DISPLAY INVISIBLE (-5515 3585);
FORCEPROP 1 LASTPIN (-5525 3575) BN 41
J 0
(-5577 3583);
DISPLAY 0.617021 (-5577 3583);
PAINT PINK (-5577 3583);
FORCEPROP 1 LAST PATH I63
J 0
(-5577 3575);
DISPLAY 0.872340 (-5577 3575);
PAINT GREEN (-5577 3575);
DISPLAY INVISIBLE (-5577 3575);
FORCEPROP 1 LAST HDL_TAP TRUE
J 0
(-5250 3450);
DISPLAY 1.595745 (-5250 3450);
PAINT GREEN (-5250 3450);
DISPLAY INVISIBLE (-5250 3450);
FORCEPROP 1 LAST BODY_TYPE PLUMBING
J 0
(-5575 3525);
DISPLAY 1.595745 (-5575 3525);
PAINT GREEN (-5575 3525);
DISPLAY INVISIBLE (-5575 3525);
FORCEPROP 2 LAST CDS_LIB mstr_standard
J 0
(-5575 3575);
PAINT MONO (-5575 3575);
DISPLAY INVISIBLE (-5575 3575);
FORCEADD TAP..6
(-5575 3625);
FORCEPROP 3 LASTPIN (-5525 3625) SIG_NAME M_F_DQ<42>
J 0
(-5515 3635);
DISPLAY 0.659574 (-5515 3635);
PAINT MONO (-5515 3635);
DISPLAY INVISIBLE (-5515 3635);
FORCEPROP 1 LASTPIN (-5525 3625) BN 42
J 0
(-5577 3633);
DISPLAY 0.617021 (-5577 3633);
PAINT PINK (-5577 3633);
FORCEPROP 1 LAST PATH I64
J 0
(-5577 3625);
DISPLAY 0.872340 (-5577 3625);
PAINT GREEN (-5577 3625);
DISPLAY INVISIBLE (-5577 3625);
FORCEPROP 1 LAST HDL_TAP TRUE
J 0
(-5250 3500);
DISPLAY 1.595745 (-5250 3500);
PAINT GREEN (-5250 3500);
DISPLAY INVISIBLE (-5250 3500);
FORCEPROP 1 LAST BODY_TYPE PLUMBING
J 0
(-5575 3575);
DISPLAY 1.595745 (-5575 3575);
PAINT GREEN (-5575 3575);
DISPLAY INVISIBLE (-5575 3575);
FORCEPROP 2 LAST CDS_LIB mstr_standard
J 0
(-5575 3625);
PAINT MONO (-5575 3625);
DISPLAY INVISIBLE (-5575 3625);
FORCEADD TAP..6
(-5575 3675);
FORCEPROP 3 LASTPIN (-5525 3675) SIG_NAME M_F_DQ<43>
J 0
(-5515 3685);
DISPLAY 0.659574 (-5515 3685);
PAINT MONO (-5515 3685);
DISPLAY INVISIBLE (-5515 3685);
FORCEPROP 1 LASTPIN (-5525 3675) BN 43
J 0
(-5577 3683);
DISPLAY 0.617021 (-5577 3683);
PAINT PINK (-5577 3683);
FORCEPROP 1 LAST PATH I65
J 0
(-5577 3675);
DISPLAY 0.872340 (-5577 3675);
PAINT GREEN (-5577 3675);
DISPLAY INVISIBLE (-5577 3675);
FORCEPROP 1 LAST HDL_TAP TRUE
J 0
(-5250 3550);
DISPLAY 1.595745 (-5250 3550);
PAINT GREEN (-5250 3550);
DISPLAY INVISIBLE (-5250 3550);
FORCEPROP 1 LAST BODY_TYPE PLUMBING
J 0
(-5575 3625);
DISPLAY 1.595745 (-5575 3625);
PAINT GREEN (-5575 3625);
DISPLAY INVISIBLE (-5575 3625);
FORCEPROP 2 LAST CDS_LIB mstr_standard
J 0
(-5575 3675);
PAINT MONO (-5575 3675);
DISPLAY INVISIBLE (-5575 3675);
FORCEADD TAP..6
(-5575 3725);
FORCEPROP 3 LASTPIN (-5525 3725) SIG_NAME M_F_DQ<44>
J 0
(-5515 3735);
DISPLAY 0.659574 (-5515 3735);
PAINT MONO (-5515 3735);
DISPLAY INVISIBLE (-5515 3735);
FORCEPROP 1 LASTPIN (-5525 3725) BN 44
J 0
(-5577 3733);
DISPLAY 0.617021 (-5577 3733);
PAINT PINK (-5577 3733);
FORCEPROP 1 LAST PATH I66
J 0
(-5577 3725);
DISPLAY 0.872340 (-5577 3725);
PAINT GREEN (-5577 3725);
DISPLAY INVISIBLE (-5577 3725);
FORCEPROP 1 LAST HDL_TAP TRUE
J 0
(-5250 3600);
DISPLAY 1.595745 (-5250 3600);
PAINT GREEN (-5250 3600);
DISPLAY INVISIBLE (-5250 3600);
FORCEPROP 1 LAST BODY_TYPE PLUMBING
J 0
(-5575 3675);
DISPLAY 1.595745 (-5575 3675);
PAINT GREEN (-5575 3675);
DISPLAY INVISIBLE (-5575 3675);
FORCEPROP 2 LAST CDS_LIB mstr_standard
J 0
(-5575 3725);
PAINT MONO (-5575 3725);
DISPLAY INVISIBLE (-5575 3725);
FORCEADD TAP..6
(-5575 3775);
FORCEPROP 3 LASTPIN (-5525 3775) SIG_NAME M_F_DQ<45>
J 0
(-5515 3785);
DISPLAY 0.659574 (-5515 3785);
PAINT MONO (-5515 3785);
DISPLAY INVISIBLE (-5515 3785);
FORCEPROP 1 LASTPIN (-5525 3775) BN 45
J 0
(-5577 3783);
DISPLAY 0.617021 (-5577 3783);
PAINT PINK (-5577 3783);
FORCEPROP 1 LAST PATH I67
J 0
(-5577 3775);
DISPLAY 0.872340 (-5577 3775);
PAINT GREEN (-5577 3775);
DISPLAY INVISIBLE (-5577 3775);
FORCEPROP 1 LAST HDL_TAP TRUE
J 0
(-5250 3650);
DISPLAY 1.595745 (-5250 3650);
PAINT GREEN (-5250 3650);
DISPLAY INVISIBLE (-5250 3650);
FORCEPROP 1 LAST BODY_TYPE PLUMBING
J 0
(-5575 3725);
DISPLAY 1.595745 (-5575 3725);
PAINT GREEN (-5575 3725);
DISPLAY INVISIBLE (-5575 3725);
FORCEPROP 2 LAST CDS_LIB mstr_standard
J 0
(-5575 3775);
PAINT MONO (-5575 3775);
DISPLAY INVISIBLE (-5575 3775);
FORCEADD TAP..6
(-5575 3825);
FORCEPROP 3 LASTPIN (-5525 3825) SIG_NAME M_F_DQ<46>
J 0
(-5515 3835);
DISPLAY 0.659574 (-5515 3835);
PAINT MONO (-5515 3835);
DISPLAY INVISIBLE (-5515 3835);
FORCEPROP 1 LASTPIN (-5525 3825) BN 46
J 0
(-5577 3833);
DISPLAY 0.617021 (-5577 3833);
PAINT PINK (-5577 3833);
FORCEPROP 1 LAST PATH I68
J 0
(-5577 3825);
DISPLAY 0.872340 (-5577 3825);
PAINT GREEN (-5577 3825);
DISPLAY INVISIBLE (-5577 3825);
FORCEPROP 1 LAST HDL_TAP TRUE
J 0
(-5250 3700);
DISPLAY 1.595745 (-5250 3700);
PAINT GREEN (-5250 3700);
DISPLAY INVISIBLE (-5250 3700);
FORCEPROP 1 LAST BODY_TYPE PLUMBING
J 0
(-5575 3775);
DISPLAY 1.595745 (-5575 3775);
PAINT GREEN (-5575 3775);
DISPLAY INVISIBLE (-5575 3775);
FORCEPROP 2 LAST CDS_LIB mstr_standard
J 0
(-5575 3825);
PAINT MONO (-5575 3825);
DISPLAY INVISIBLE (-5575 3825);
FORCEADD TAP..6
(-5575 3875);
FORCEPROP 3 LASTPIN (-5525 3875) SIG_NAME M_F_DQ<47>
J 0
(-5515 3885);
DISPLAY 0.659574 (-5515 3885);
PAINT MONO (-5515 3885);
DISPLAY INVISIBLE (-5515 3885);
FORCEPROP 1 LASTPIN (-5525 3875) BN 47
J 0
(-5577 3883);
DISPLAY 0.617021 (-5577 3883);
PAINT PINK (-5577 3883);
FORCEPROP 1 LAST PATH I69
J 0
(-5577 3875);
DISPLAY 0.872340 (-5577 3875);
PAINT GREEN (-5577 3875);
DISPLAY INVISIBLE (-5577 3875);
FORCEPROP 1 LAST HDL_TAP TRUE
J 0
(-5250 3750);
DISPLAY 1.595745 (-5250 3750);
PAINT GREEN (-5250 3750);
DISPLAY INVISIBLE (-5250 3750);
FORCEPROP 1 LAST BODY_TYPE PLUMBING
J 0
(-5575 3825);
DISPLAY 1.595745 (-5575 3825);
PAINT GREEN (-5575 3825);
DISPLAY INVISIBLE (-5575 3825);
FORCEPROP 2 LAST CDS_LIB mstr_standard
J 0
(-5575 3875);
PAINT MONO (-5575 3875);
DISPLAY INVISIBLE (-5575 3875);
FORCEADD TAP..6
(-5575 775);
FORCEPROP 3 LASTPIN (-5525 775) SIG_NAME M_F_CLK_DN<3>
J 0
(-5515 785);
DISPLAY 0.659574 (-5515 785);
PAINT MONO (-5515 785);
DISPLAY INVISIBLE (-5515 785);
FORCEPROP 1 LASTPIN (-5525 775) BN 3
J 0
(-5577 783);
DISPLAY 0.617021 (-5577 783);
PAINT PINK (-5577 783);
FORCEPROP 1 LAST PATH I7
J 0
(-5577 775);
DISPLAY 0.872340 (-5577 775);
PAINT GREEN (-5577 775);
DISPLAY INVISIBLE (-5577 775);
FORCEPROP 1 LAST HDL_TAP TRUE
J 0
(-5250 650);
DISPLAY 1.595745 (-5250 650);
PAINT GREEN (-5250 650);
DISPLAY INVISIBLE (-5250 650);
FORCEPROP 1 LAST BODY_TYPE PLUMBING
J 0
(-5575 725);
DISPLAY 1.595745 (-5575 725);
PAINT GREEN (-5575 725);
DISPLAY INVISIBLE (-5575 725);
FORCEPROP 2 LAST CDS_LIB mstr_standard
J 0
(-5575 775);
PAINT MONO (-5575 775);
DISPLAY INVISIBLE (-5575 775);
FORCEADD TAP..6
(-5575 3925);
FORCEPROP 3 LASTPIN (-5525 3925) SIG_NAME M_F_DQ<48>
J 0
(-5515 3935);
DISPLAY 0.659574 (-5515 3935);
PAINT MONO (-5515 3935);
DISPLAY INVISIBLE (-5515 3935);
FORCEPROP 1 LASTPIN (-5525 3925) BN 48
J 0
(-5577 3933);
DISPLAY 0.617021 (-5577 3933);
PAINT PINK (-5577 3933);
FORCEPROP 1 LAST PATH I70
J 0
(-5577 3925);
DISPLAY 0.872340 (-5577 3925);
PAINT GREEN (-5577 3925);
DISPLAY INVISIBLE (-5577 3925);
FORCEPROP 1 LAST HDL_TAP TRUE
J 0
(-5250 3800);
DISPLAY 1.595745 (-5250 3800);
PAINT GREEN (-5250 3800);
DISPLAY INVISIBLE (-5250 3800);
FORCEPROP 1 LAST BODY_TYPE PLUMBING
J 0
(-5575 3875);
DISPLAY 1.595745 (-5575 3875);
PAINT GREEN (-5575 3875);
DISPLAY INVISIBLE (-5575 3875);
FORCEPROP 2 LAST CDS_LIB mstr_standard
J 0
(-5575 3925);
PAINT MONO (-5575 3925);
DISPLAY INVISIBLE (-5575 3925);
FORCEADD TAP..6
(-5575 3975);
FORCEPROP 3 LASTPIN (-5525 3975) SIG_NAME M_F_DQ<49>
J 0
(-5515 3985);
DISPLAY 0.659574 (-5515 3985);
PAINT MONO (-5515 3985);
DISPLAY INVISIBLE (-5515 3985);
FORCEPROP 1 LASTPIN (-5525 3975) BN 49
J 0
(-5577 3983);
DISPLAY 0.617021 (-5577 3983);
PAINT PINK (-5577 3983);
FORCEPROP 1 LAST PATH I71
J 0
(-5577 3975);
DISPLAY 0.872340 (-5577 3975);
PAINT GREEN (-5577 3975);
DISPLAY INVISIBLE (-5577 3975);
FORCEPROP 1 LAST HDL_TAP TRUE
J 0
(-5250 3850);
DISPLAY 1.595745 (-5250 3850);
PAINT GREEN (-5250 3850);
DISPLAY INVISIBLE (-5250 3850);
FORCEPROP 1 LAST BODY_TYPE PLUMBING
J 0
(-5575 3925);
DISPLAY 1.595745 (-5575 3925);
PAINT GREEN (-5575 3925);
DISPLAY INVISIBLE (-5575 3925);
FORCEPROP 2 LAST CDS_LIB mstr_standard
J 0
(-5575 3975);
PAINT MONO (-5575 3975);
DISPLAY INVISIBLE (-5575 3975);
FORCEADD TAP..6
(-5575 4025);
FORCEPROP 3 LASTPIN (-5525 4025) SIG_NAME M_F_DQ<50>
J 0
(-5515 4035);
DISPLAY 0.659574 (-5515 4035);
PAINT MONO (-5515 4035);
DISPLAY INVISIBLE (-5515 4035);
FORCEPROP 1 LASTPIN (-5525 4025) BN 50
J 0
(-5577 4033);
DISPLAY 0.617021 (-5577 4033);
PAINT PINK (-5577 4033);
FORCEPROP 1 LAST PATH I72
J 0
(-5577 4025);
DISPLAY 0.872340 (-5577 4025);
PAINT GREEN (-5577 4025);
DISPLAY INVISIBLE (-5577 4025);
FORCEPROP 1 LAST HDL_TAP TRUE
J 0
(-5250 3900);
DISPLAY 1.595745 (-5250 3900);
PAINT GREEN (-5250 3900);
DISPLAY INVISIBLE (-5250 3900);
FORCEPROP 1 LAST BODY_TYPE PLUMBING
J 0
(-5575 3975);
DISPLAY 1.595745 (-5575 3975);
PAINT GREEN (-5575 3975);
DISPLAY INVISIBLE (-5575 3975);
FORCEPROP 2 LAST CDS_LIB mstr_standard
J 0
(-5575 4025);
PAINT MONO (-5575 4025);
DISPLAY INVISIBLE (-5575 4025);
FORCEADD OFFPAGE..6
(-6425 4800);
FORCEPROP 2 LAST $XR1 54 
J 0
(-6764 4800);
DISPLAY 0.638298 (-6764 4800);
PAINT MONO (-6764 4800);
FORCEPROP 2 LAST $XR0 53 
J 0
(-6674 4800);
DISPLAY 0.638298 (-6674 4800);
PAINT MONO (-6674 4800);
FORCEPROP 2 LAST PATH I73
J 0
(-6375 4875);
DISPLAY 1.021277 (-6375 4875);
PAINT ORANGE (-6375 4875);
DISPLAY INVISIBLE (-6375 4875);
FORCEPROP 1 LAST COMMENT_BODY TRUE
J 0
(-6325 4725);
DISPLAY 1.170213 (-6325 4725);
PAINT GREEN (-6325 4725);
DISPLAY INVISIBLE (-6325 4725);
FORCEPROP 1 LAST OFFPAGE TRUE
J 0
(-6100 4675);
DISPLAY 1.170213 (-6100 4675);
PAINT GREEN (-6100 4675);
DISPLAY INVISIBLE (-6100 4675);
FORCEPROP 2 LAST CDS_LIB mstr_standard
J 0
(-6425 4800);
PAINT MONO (-6425 4800);
DISPLAY INVISIBLE (-6425 4800);
FORCEADD TAP..6
(-5575 4075);
FORCEPROP 3 LASTPIN (-5525 4075) SIG_NAME M_F_DQ<51>
J 0
(-5515 4085);
DISPLAY 0.659574 (-5515 4085);
PAINT MONO (-5515 4085);
DISPLAY INVISIBLE (-5515 4085);
FORCEPROP 1 LASTPIN (-5525 4075) BN 51
J 0
(-5577 4083);
DISPLAY 0.617021 (-5577 4083);
PAINT PINK (-5577 4083);
FORCEPROP 1 LAST PATH I74
J 0
(-5577 4075);
DISPLAY 0.872340 (-5577 4075);
PAINT GREEN (-5577 4075);
DISPLAY INVISIBLE (-5577 4075);
FORCEPROP 1 LAST HDL_TAP TRUE
J 0
(-5250 3950);
DISPLAY 1.595745 (-5250 3950);
PAINT GREEN (-5250 3950);
DISPLAY INVISIBLE (-5250 3950);
FORCEPROP 1 LAST BODY_TYPE PLUMBING
J 0
(-5575 4025);
DISPLAY 1.595745 (-5575 4025);
PAINT GREEN (-5575 4025);
DISPLAY INVISIBLE (-5575 4025);
FORCEPROP 2 LAST CDS_LIB mstr_standard
J 0
(-5575 4075);
PAINT MONO (-5575 4075);
DISPLAY INVISIBLE (-5575 4075);
FORCEADD TAP..6
(-5575 4125);
FORCEPROP 3 LASTPIN (-5525 4125) SIG_NAME M_F_DQ<52>
J 0
(-5515 4135);
DISPLAY 0.659574 (-5515 4135);
PAINT MONO (-5515 4135);
DISPLAY INVISIBLE (-5515 4135);
FORCEPROP 1 LASTPIN (-5525 4125) BN 52
J 0
(-5577 4133);
DISPLAY 0.617021 (-5577 4133);
PAINT PINK (-5577 4133);
FORCEPROP 1 LAST PATH I75
J 0
(-5577 4125);
DISPLAY 0.872340 (-5577 4125);
PAINT GREEN (-5577 4125);
DISPLAY INVISIBLE (-5577 4125);
FORCEPROP 1 LAST HDL_TAP TRUE
J 0
(-5250 4000);
DISPLAY 1.595745 (-5250 4000);
PAINT GREEN (-5250 4000);
DISPLAY INVISIBLE (-5250 4000);
FORCEPROP 1 LAST BODY_TYPE PLUMBING
J 0
(-5575 4075);
DISPLAY 1.595745 (-5575 4075);
PAINT GREEN (-5575 4075);
DISPLAY INVISIBLE (-5575 4075);
FORCEPROP 2 LAST CDS_LIB mstr_standard
J 0
(-5575 4125);
PAINT MONO (-5575 4125);
DISPLAY INVISIBLE (-5575 4125);
FORCEADD TAP..6
(-5575 4175);
FORCEPROP 3 LASTPIN (-5525 4175) SIG_NAME M_F_DQ<53>
J 0
(-5515 4185);
DISPLAY 0.659574 (-5515 4185);
PAINT MONO (-5515 4185);
DISPLAY INVISIBLE (-5515 4185);
FORCEPROP 1 LASTPIN (-5525 4175) BN 53
J 0
(-5577 4183);
DISPLAY 0.617021 (-5577 4183);
PAINT PINK (-5577 4183);
FORCEPROP 1 LAST PATH I76
J 0
(-5577 4175);
DISPLAY 0.872340 (-5577 4175);
PAINT GREEN (-5577 4175);
DISPLAY INVISIBLE (-5577 4175);
FORCEPROP 1 LAST HDL_TAP TRUE
J 0
(-5250 4050);
DISPLAY 1.595745 (-5250 4050);
PAINT GREEN (-5250 4050);
DISPLAY INVISIBLE (-5250 4050);
FORCEPROP 1 LAST BODY_TYPE PLUMBING
J 0
(-5575 4125);
DISPLAY 1.595745 (-5575 4125);
PAINT GREEN (-5575 4125);
DISPLAY INVISIBLE (-5575 4125);
FORCEPROP 2 LAST CDS_LIB mstr_standard
J 0
(-5575 4175);
PAINT MONO (-5575 4175);
DISPLAY INVISIBLE (-5575 4175);
FORCEADD TAP..6
(-5575 4225);
FORCEPROP 3 LASTPIN (-5525 4225) SIG_NAME M_F_DQ<54>
J 0
(-5515 4235);
DISPLAY 0.659574 (-5515 4235);
PAINT MONO (-5515 4235);
DISPLAY INVISIBLE (-5515 4235);
FORCEPROP 1 LASTPIN (-5525 4225) BN 54
J 0
(-5577 4233);
DISPLAY 0.617021 (-5577 4233);
PAINT PINK (-5577 4233);
FORCEPROP 1 LAST PATH I77
J 0
(-5577 4225);
DISPLAY 0.872340 (-5577 4225);
PAINT GREEN (-5577 4225);
DISPLAY INVISIBLE (-5577 4225);
FORCEPROP 1 LAST HDL_TAP TRUE
J 0
(-5250 4100);
DISPLAY 1.595745 (-5250 4100);
PAINT GREEN (-5250 4100);
DISPLAY INVISIBLE (-5250 4100);
FORCEPROP 1 LAST BODY_TYPE PLUMBING
J 0
(-5575 4175);
DISPLAY 1.595745 (-5575 4175);
PAINT GREEN (-5575 4175);
DISPLAY INVISIBLE (-5575 4175);
FORCEPROP 2 LAST CDS_LIB mstr_standard
J 0
(-5575 4225);
PAINT MONO (-5575 4225);
DISPLAY INVISIBLE (-5575 4225);
FORCEADD TAP..6
(-5575 4275);
FORCEPROP 3 LASTPIN (-5525 4275) SIG_NAME M_F_DQ<55>
J 0
(-5515 4285);
DISPLAY 0.659574 (-5515 4285);
PAINT MONO (-5515 4285);
DISPLAY INVISIBLE (-5515 4285);
FORCEPROP 1 LASTPIN (-5525 4275) BN 55
J 0
(-5577 4283);
DISPLAY 0.617021 (-5577 4283);
PAINT PINK (-5577 4283);
FORCEPROP 1 LAST PATH I78
J 0
(-5577 4275);
DISPLAY 0.872340 (-5577 4275);
PAINT GREEN (-5577 4275);
DISPLAY INVISIBLE (-5577 4275);
FORCEPROP 1 LAST HDL_TAP TRUE
J 0
(-5250 4150);
DISPLAY 1.595745 (-5250 4150);
PAINT GREEN (-5250 4150);
DISPLAY INVISIBLE (-5250 4150);
FORCEPROP 1 LAST BODY_TYPE PLUMBING
J 0
(-5575 4225);
DISPLAY 1.595745 (-5575 4225);
PAINT GREEN (-5575 4225);
DISPLAY INVISIBLE (-5575 4225);
FORCEPROP 2 LAST CDS_LIB mstr_standard
J 0
(-5575 4275);
PAINT MONO (-5575 4275);
DISPLAY INVISIBLE (-5575 4275);
FORCEADD TAP..6
(-5575 4325);
FORCEPROP 3 LASTPIN (-5525 4325) SIG_NAME M_F_DQ<56>
J 0
(-5515 4335);
DISPLAY 0.659574 (-5515 4335);
PAINT MONO (-5515 4335);
DISPLAY INVISIBLE (-5515 4335);
FORCEPROP 1 LASTPIN (-5525 4325) BN 56
J 0
(-5577 4333);
DISPLAY 0.617021 (-5577 4333);
PAINT PINK (-5577 4333);
FORCEPROP 1 LAST PATH I79
J 0
(-5577 4325);
DISPLAY 0.872340 (-5577 4325);
PAINT GREEN (-5577 4325);
DISPLAY INVISIBLE (-5577 4325);
FORCEPROP 1 LAST HDL_TAP TRUE
J 0
(-5250 4200);
DISPLAY 1.595745 (-5250 4200);
PAINT GREEN (-5250 4200);
DISPLAY INVISIBLE (-5250 4200);
FORCEPROP 1 LAST BODY_TYPE PLUMBING
J 0
(-5575 4275);
DISPLAY 1.595745 (-5575 4275);
PAINT GREEN (-5575 4275);
DISPLAY INVISIBLE (-5575 4275);
FORCEPROP 2 LAST CDS_LIB mstr_standard
J 0
(-5575 4325);
PAINT MONO (-5575 4325);
DISPLAY INVISIBLE (-5575 4325);
FORCEADD TAP..6
(-5575 725);
FORCEPROP 3 LASTPIN (-5525 725) SIG_NAME M_F_CLK_DN<2>
J 0
(-5515 735);
DISPLAY 0.659574 (-5515 735);
PAINT MONO (-5515 735);
DISPLAY INVISIBLE (-5515 735);
FORCEPROP 1 LASTPIN (-5525 725) BN 2
J 0
(-5577 733);
DISPLAY 0.617021 (-5577 733);
PAINT PINK (-5577 733);
FORCEPROP 1 LAST PATH I8
J 0
(-5577 725);
DISPLAY 0.872340 (-5577 725);
PAINT GREEN (-5577 725);
DISPLAY INVISIBLE (-5577 725);
FORCEPROP 1 LAST HDL_TAP TRUE
J 0
(-5250 600);
DISPLAY 1.595745 (-5250 600);
PAINT GREEN (-5250 600);
DISPLAY INVISIBLE (-5250 600);
FORCEPROP 1 LAST BODY_TYPE PLUMBING
J 0
(-5575 675);
DISPLAY 1.595745 (-5575 675);
PAINT GREEN (-5575 675);
DISPLAY INVISIBLE (-5575 675);
FORCEPROP 2 LAST CDS_LIB mstr_standard
J 0
(-5575 725);
PAINT MONO (-5575 725);
DISPLAY INVISIBLE (-5575 725);
FORCEADD TAP..6
(-5575 4375);
FORCEPROP 3 LASTPIN (-5525 4375) SIG_NAME M_F_DQ<57>
J 0
(-5515 4385);
DISPLAY 0.659574 (-5515 4385);
PAINT MONO (-5515 4385);
DISPLAY INVISIBLE (-5515 4385);
FORCEPROP 1 LASTPIN (-5525 4375) BN 57
J 0
(-5577 4383);
DISPLAY 0.617021 (-5577 4383);
PAINT PINK (-5577 4383);
FORCEPROP 1 LAST PATH I80
J 0
(-5577 4375);
DISPLAY 0.872340 (-5577 4375);
PAINT GREEN (-5577 4375);
DISPLAY INVISIBLE (-5577 4375);
FORCEPROP 1 LAST HDL_TAP TRUE
J 0
(-5250 4250);
DISPLAY 1.595745 (-5250 4250);
PAINT GREEN (-5250 4250);
DISPLAY INVISIBLE (-5250 4250);
FORCEPROP 1 LAST BODY_TYPE PLUMBING
J 0
(-5575 4325);
DISPLAY 1.595745 (-5575 4325);
PAINT GREEN (-5575 4325);
DISPLAY INVISIBLE (-5575 4325);
FORCEPROP 2 LAST CDS_LIB mstr_standard
J 0
(-5575 4375);
PAINT MONO (-5575 4375);
DISPLAY INVISIBLE (-5575 4375);
FORCEADD TAP..6
(-5575 4425);
FORCEPROP 3 LASTPIN (-5525 4425) SIG_NAME M_F_DQ<58>
J 0
(-5515 4435);
DISPLAY 0.659574 (-5515 4435);
PAINT MONO (-5515 4435);
DISPLAY INVISIBLE (-5515 4435);
FORCEPROP 1 LASTPIN (-5525 4425) BN 58
J 0
(-5577 4433);
DISPLAY 0.617021 (-5577 4433);
PAINT PINK (-5577 4433);
FORCEPROP 1 LAST PATH I81
J 0
(-5577 4425);
DISPLAY 0.872340 (-5577 4425);
PAINT GREEN (-5577 4425);
DISPLAY INVISIBLE (-5577 4425);
FORCEPROP 1 LAST HDL_TAP TRUE
J 0
(-5250 4300);
DISPLAY 1.595745 (-5250 4300);
PAINT GREEN (-5250 4300);
DISPLAY INVISIBLE (-5250 4300);
FORCEPROP 1 LAST BODY_TYPE PLUMBING
J 0
(-5575 4375);
DISPLAY 1.595745 (-5575 4375);
PAINT GREEN (-5575 4375);
DISPLAY INVISIBLE (-5575 4375);
FORCEPROP 2 LAST CDS_LIB mstr_standard
J 0
(-5575 4425);
PAINT MONO (-5575 4425);
DISPLAY INVISIBLE (-5575 4425);
FORCEADD TAP..6
(-5575 4475);
FORCEPROP 3 LASTPIN (-5525 4475) SIG_NAME M_F_DQ<59>
J 0
(-5515 4485);
DISPLAY 0.659574 (-5515 4485);
PAINT MONO (-5515 4485);
DISPLAY INVISIBLE (-5515 4485);
FORCEPROP 1 LASTPIN (-5525 4475) BN 59
J 0
(-5577 4483);
DISPLAY 0.617021 (-5577 4483);
PAINT PINK (-5577 4483);
FORCEPROP 1 LAST PATH I82
J 0
(-5577 4475);
DISPLAY 0.872340 (-5577 4475);
PAINT GREEN (-5577 4475);
DISPLAY INVISIBLE (-5577 4475);
FORCEPROP 1 LAST HDL_TAP TRUE
J 0
(-5250 4350);
DISPLAY 1.595745 (-5250 4350);
PAINT GREEN (-5250 4350);
DISPLAY INVISIBLE (-5250 4350);
FORCEPROP 1 LAST BODY_TYPE PLUMBING
J 0
(-5575 4425);
DISPLAY 1.595745 (-5575 4425);
PAINT GREEN (-5575 4425);
DISPLAY INVISIBLE (-5575 4425);
FORCEPROP 2 LAST CDS_LIB mstr_standard
J 0
(-5575 4475);
PAINT MONO (-5575 4475);
DISPLAY INVISIBLE (-5575 4475);
FORCEADD TAP..6
(-5575 4525);
FORCEPROP 3 LASTPIN (-5525 4525) SIG_NAME M_F_DQ<60>
J 0
(-5515 4535);
DISPLAY 0.659574 (-5515 4535);
PAINT MONO (-5515 4535);
DISPLAY INVISIBLE (-5515 4535);
FORCEPROP 1 LASTPIN (-5525 4525) BN 60
J 0
(-5577 4533);
DISPLAY 0.617021 (-5577 4533);
PAINT PINK (-5577 4533);
FORCEPROP 1 LAST PATH I83
J 0
(-5577 4525);
DISPLAY 0.872340 (-5577 4525);
PAINT GREEN (-5577 4525);
DISPLAY INVISIBLE (-5577 4525);
FORCEPROP 1 LAST HDL_TAP TRUE
J 0
(-5250 4400);
DISPLAY 1.595745 (-5250 4400);
PAINT GREEN (-5250 4400);
DISPLAY INVISIBLE (-5250 4400);
FORCEPROP 1 LAST BODY_TYPE PLUMBING
J 0
(-5575 4475);
DISPLAY 1.595745 (-5575 4475);
PAINT GREEN (-5575 4475);
DISPLAY INVISIBLE (-5575 4475);
FORCEPROP 2 LAST CDS_LIB mstr_standard
J 0
(-5575 4525);
PAINT MONO (-5575 4525);
DISPLAY INVISIBLE (-5575 4525);
FORCEADD TAP..6
(-5575 4575);
FORCEPROP 3 LASTPIN (-5525 4575) SIG_NAME M_F_DQ<61>
J 0
(-5515 4585);
DISPLAY 0.659574 (-5515 4585);
PAINT MONO (-5515 4585);
DISPLAY INVISIBLE (-5515 4585);
FORCEPROP 1 LASTPIN (-5525 4575) BN 61
J 0
(-5577 4583);
DISPLAY 0.617021 (-5577 4583);
PAINT PINK (-5577 4583);
FORCEPROP 1 LAST PATH I84
J 0
(-5577 4575);
DISPLAY 0.872340 (-5577 4575);
PAINT GREEN (-5577 4575);
DISPLAY INVISIBLE (-5577 4575);
FORCEPROP 1 LAST HDL_TAP TRUE
J 0
(-5250 4450);
DISPLAY 1.595745 (-5250 4450);
PAINT GREEN (-5250 4450);
DISPLAY INVISIBLE (-5250 4450);
FORCEPROP 1 LAST BODY_TYPE PLUMBING
J 0
(-5575 4525);
DISPLAY 1.595745 (-5575 4525);
PAINT GREEN (-5575 4525);
DISPLAY INVISIBLE (-5575 4525);
FORCEPROP 2 LAST CDS_LIB mstr_standard
J 0
(-5575 4575);
PAINT MONO (-5575 4575);
DISPLAY INVISIBLE (-5575 4575);
FORCEADD TAP..6
(-5575 4625);
FORCEPROP 3 LASTPIN (-5525 4625) SIG_NAME M_F_DQ<62>
J 0
(-5515 4635);
DISPLAY 0.659574 (-5515 4635);
PAINT MONO (-5515 4635);
DISPLAY INVISIBLE (-5515 4635);
FORCEPROP 1 LASTPIN (-5525 4625) BN 62
J 0
(-5577 4633);
DISPLAY 0.617021 (-5577 4633);
PAINT PINK (-5577 4633);
FORCEPROP 1 LAST PATH I85
J 0
(-5577 4625);
DISPLAY 0.872340 (-5577 4625);
PAINT GREEN (-5577 4625);
DISPLAY INVISIBLE (-5577 4625);
FORCEPROP 1 LAST HDL_TAP TRUE
J 0
(-5250 4500);
DISPLAY 1.595745 (-5250 4500);
PAINT GREEN (-5250 4500);
DISPLAY INVISIBLE (-5250 4500);
FORCEPROP 1 LAST BODY_TYPE PLUMBING
J 0
(-5575 4575);
DISPLAY 1.595745 (-5575 4575);
PAINT GREEN (-5575 4575);
DISPLAY INVISIBLE (-5575 4575);
FORCEPROP 2 LAST CDS_LIB mstr_standard
J 0
(-5575 4625);
PAINT MONO (-5575 4625);
DISPLAY INVISIBLE (-5575 4625);
FORCEADD TAP..6
(-5575 4675);
FORCEPROP 3 LASTPIN (-5525 4675) SIG_NAME M_F_DQ<63>
J 0
(-5515 4685);
DISPLAY 0.659574 (-5515 4685);
PAINT MONO (-5515 4685);
DISPLAY INVISIBLE (-5515 4685);
FORCEPROP 1 LASTPIN (-5525 4675) BN 63
J 0
(-5577 4683);
DISPLAY 0.617021 (-5577 4683);
PAINT PINK (-5577 4683);
FORCEPROP 1 LAST PATH I86
J 0
(-5577 4675);
DISPLAY 0.872340 (-5577 4675);
PAINT GREEN (-5577 4675);
DISPLAY INVISIBLE (-5577 4675);
FORCEPROP 1 LAST HDL_TAP TRUE
J 0
(-5250 4550);
DISPLAY 1.595745 (-5250 4550);
PAINT GREEN (-5250 4550);
DISPLAY INVISIBLE (-5250 4550);
FORCEPROP 1 LAST BODY_TYPE PLUMBING
J 0
(-5575 4625);
DISPLAY 1.595745 (-5575 4625);
PAINT GREEN (-5575 4625);
DISPLAY INVISIBLE (-5575 4625);
FORCEPROP 2 LAST CDS_LIB mstr_standard
J 0
(-5575 4675);
PAINT MONO (-5575 4675);
DISPLAY INVISIBLE (-5575 4675);
FORCEADD TAP..6
R 2
(-2850 825);
FORCEPROP 3 LASTPIN (-2900 825) SIG_NAME M_F_BG<0>
J 0
(-2890 835);
DISPLAY 0.659574 (-2890 835);
PAINT MONO (-2890 835);
DISPLAY INVISIBLE (-2890 835);
FORCEPROP 1 LASTPIN (-2900 825) BN 0
J 2
(-2848 833);
DISPLAY 0.617021 (-2848 833);
PAINT PINK (-2848 833);
FORCEPROP 1 LAST PATH I87
J 2
(-2848 825);
DISPLAY 0.872340 (-2848 825);
PAINT GREEN (-2848 825);
DISPLAY INVISIBLE (-2848 825);
FORCEPROP 1 LAST HDL_TAP TRUE
J 2
(-3175 700);
DISPLAY 1.595745 (-3175 700);
PAINT GREEN (-3175 700);
DISPLAY INVISIBLE (-3175 700);
FORCEPROP 1 LAST BODY_TYPE PLUMBING
J 2
(-2850 775);
DISPLAY 1.595745 (-2850 775);
PAINT GREEN (-2850 775);
DISPLAY INVISIBLE (-2850 775);
FORCEPROP 2 LAST CDS_LIB mstr_standard
J 0
(-2850 825);
PAINT MONO (-2850 825);
DISPLAY INVISIBLE (-2850 825);
FORCEADD TAP..6
R 2
(-2850 775);
FORCEPROP 3 LASTPIN (-2900 775) SIG_NAME M_F_BA<1>
J 0
(-2890 785);
DISPLAY 0.659574 (-2890 785);
PAINT MONO (-2890 785);
DISPLAY INVISIBLE (-2890 785);
FORCEPROP 1 LASTPIN (-2900 775) BN 1
J 2
(-2848 783);
DISPLAY 0.617021 (-2848 783);
PAINT PINK (-2848 783);
FORCEPROP 1 LAST PATH I88
J 2
(-2848 775);
DISPLAY 0.872340 (-2848 775);
PAINT GREEN (-2848 775);
DISPLAY INVISIBLE (-2848 775);
FORCEPROP 1 LAST HDL_TAP TRUE
J 2
(-3175 650);
DISPLAY 1.595745 (-3175 650);
PAINT GREEN (-3175 650);
DISPLAY INVISIBLE (-3175 650);
FORCEPROP 1 LAST BODY_TYPE PLUMBING
J 2
(-2850 725);
DISPLAY 1.595745 (-2850 725);
PAINT GREEN (-2850 725);
DISPLAY INVISIBLE (-2850 725);
FORCEPROP 2 LAST CDS_LIB mstr_standard
J 0
(-2850 775);
PAINT MONO (-2850 775);
DISPLAY INVISIBLE (-2850 775);
FORCEADD TAP..6
R 2
(-2850 725);
FORCEPROP 3 LASTPIN (-2900 725) SIG_NAME M_F_BA<0>
J 0
(-2890 735);
DISPLAY 0.659574 (-2890 735);
PAINT MONO (-2890 735);
DISPLAY INVISIBLE (-2890 735);
FORCEPROP 1 LASTPIN (-2900 725) BN 0
J 2
(-2848 733);
DISPLAY 0.617021 (-2848 733);
PAINT PINK (-2848 733);
FORCEPROP 1 LAST PATH I89
J 2
(-2848 725);
DISPLAY 0.872340 (-2848 725);
PAINT GREEN (-2848 725);
DISPLAY INVISIBLE (-2848 725);
FORCEPROP 1 LAST HDL_TAP TRUE
J 2
(-3175 600);
DISPLAY 1.595745 (-3175 600);
PAINT GREEN (-3175 600);
DISPLAY INVISIBLE (-3175 600);
FORCEPROP 1 LAST BODY_TYPE PLUMBING
J 2
(-2850 675);
DISPLAY 1.595745 (-2850 675);
PAINT GREEN (-2850 675);
DISPLAY INVISIBLE (-2850 675);
FORCEPROP 2 LAST CDS_LIB mstr_standard
J 0
(-2850 725);
PAINT MONO (-2850 725);
DISPLAY INVISIBLE (-2850 725);
FORCEADD TAP..6
(-5575 825);
FORCEPROP 3 LASTPIN (-5525 825) SIG_NAME M_F_CLK_DP<0>
J 0
(-5515 835);
DISPLAY 0.659574 (-5515 835);
PAINT MONO (-5515 835);
DISPLAY INVISIBLE (-5515 835);
FORCEPROP 1 LASTPIN (-5525 825) BN 0
J 0
(-5577 833);
DISPLAY 0.617021 (-5577 833);
PAINT PINK (-5577 833);
FORCEPROP 1 LAST PATH I9
J 0
(-5577 825);
DISPLAY 0.872340 (-5577 825);
PAINT GREEN (-5577 825);
DISPLAY INVISIBLE (-5577 825);
FORCEPROP 1 LAST HDL_TAP TRUE
J 0
(-5250 700);
DISPLAY 1.595745 (-5250 700);
PAINT GREEN (-5250 700);
DISPLAY INVISIBLE (-5250 700);
FORCEPROP 1 LAST BODY_TYPE PLUMBING
J 0
(-5575 775);
DISPLAY 1.595745 (-5575 775);
PAINT GREEN (-5575 775);
DISPLAY INVISIBLE (-5575 775);
FORCEPROP 2 LAST CDS_LIB mstr_standard
J 0
(-5575 825);
PAINT MONO (-5575 825);
DISPLAY INVISIBLE (-5575 825);
FORCEADD TAP..6
R 2
(-2850 875);
FORCEPROP 3 LASTPIN (-2900 875) SIG_NAME M_F_BG<1>
J 0
(-2890 885);
DISPLAY 0.659574 (-2890 885);
PAINT MONO (-2890 885);
DISPLAY INVISIBLE (-2890 885);
FORCEPROP 1 LASTPIN (-2900 875) BN 1
J 2
(-2848 883);
DISPLAY 0.617021 (-2848 883);
PAINT PINK (-2848 883);
FORCEPROP 1 LAST PATH I90
J 2
(-2848 875);
DISPLAY 0.872340 (-2848 875);
PAINT GREEN (-2848 875);
DISPLAY INVISIBLE (-2848 875);
FORCEPROP 1 LAST HDL_TAP TRUE
J 2
(-3175 750);
DISPLAY 1.595745 (-3175 750);
PAINT GREEN (-3175 750);
DISPLAY INVISIBLE (-3175 750);
FORCEPROP 1 LAST BODY_TYPE PLUMBING
J 2
(-2850 825);
DISPLAY 1.595745 (-2850 825);
PAINT GREEN (-2850 825);
DISPLAY INVISIBLE (-2850 825);
FORCEPROP 2 LAST CDS_LIB mstr_standard
J 0
(-2850 875);
PAINT MONO (-2850 875);
DISPLAY INVISIBLE (-2850 875);
FORCEADD TAP..6
R 2
(-2850 1025);
FORCEPROP 3 LASTPIN (-2900 1025) SIG_NAME M_F_CS_N<1>
J 0
(-2890 1035);
DISPLAY 0.659574 (-2890 1035);
PAINT MONO (-2890 1035);
DISPLAY INVISIBLE (-2890 1035);
FORCEPROP 1 LASTPIN (-2900 1025) BN 1
J 2
(-2848 1033);
DISPLAY 0.617021 (-2848 1033);
PAINT PINK (-2848 1033);
FORCEPROP 1 LAST PATH I91
J 2
(-2848 1025);
DISPLAY 0.872340 (-2848 1025);
PAINT GREEN (-2848 1025);
DISPLAY INVISIBLE (-2848 1025);
FORCEPROP 1 LAST HDL_TAP TRUE
J 2
(-3175 900);
DISPLAY 1.595745 (-3175 900);
PAINT GREEN (-3175 900);
DISPLAY INVISIBLE (-3175 900);
FORCEPROP 1 LAST BODY_TYPE PLUMBING
J 2
(-2850 975);
DISPLAY 1.595745 (-2850 975);
PAINT GREEN (-2850 975);
DISPLAY INVISIBLE (-2850 975);
FORCEPROP 2 LAST CDS_LIB mstr_standard
J 0
(-2850 1025);
PAINT MONO (-2850 1025);
DISPLAY INVISIBLE (-2850 1025);
FORCEADD TAP..6
R 2
(-2850 975);
FORCEPROP 3 LASTPIN (-2900 975) SIG_NAME M_F_CS_N<0>
J 0
(-2890 985);
DISPLAY 0.659574 (-2890 985);
PAINT MONO (-2890 985);
DISPLAY INVISIBLE (-2890 985);
FORCEPROP 1 LASTPIN (-2900 975) BN 0
J 2
(-2848 983);
DISPLAY 0.617021 (-2848 983);
PAINT PINK (-2848 983);
FORCEPROP 1 LAST PATH I92
J 2
(-2848 975);
DISPLAY 0.872340 (-2848 975);
PAINT GREEN (-2848 975);
DISPLAY INVISIBLE (-2848 975);
FORCEPROP 1 LAST HDL_TAP TRUE
J 2
(-3175 850);
DISPLAY 1.595745 (-3175 850);
PAINT GREEN (-3175 850);
DISPLAY INVISIBLE (-3175 850);
FORCEPROP 1 LAST BODY_TYPE PLUMBING
J 2
(-2850 925);
DISPLAY 1.595745 (-2850 925);
PAINT GREEN (-2850 925);
DISPLAY INVISIBLE (-2850 925);
FORCEPROP 2 LAST CDS_LIB mstr_standard
J 0
(-2850 975);
PAINT MONO (-2850 975);
DISPLAY INVISIBLE (-2850 975);
FORCEADD TAP..6
R 2
(-2850 1075);
FORCEPROP 3 LASTPIN (-2900 1075) SIG_NAME M_F_CS_N<2>
J 0
(-2890 1085);
DISPLAY 0.659574 (-2890 1085);
PAINT MONO (-2890 1085);
DISPLAY INVISIBLE (-2890 1085);
FORCEPROP 1 LASTPIN (-2900 1075) BN 2
J 2
(-2848 1083);
DISPLAY 0.617021 (-2848 1083);
PAINT PINK (-2848 1083);
FORCEPROP 1 LAST PATH I93
J 2
(-2848 1075);
DISPLAY 0.872340 (-2848 1075);
PAINT GREEN (-2848 1075);
DISPLAY INVISIBLE (-2848 1075);
FORCEPROP 1 LAST HDL_TAP TRUE
J 2
(-3175 950);
DISPLAY 1.595745 (-3175 950);
PAINT GREEN (-3175 950);
DISPLAY INVISIBLE (-3175 950);
FORCEPROP 1 LAST BODY_TYPE PLUMBING
J 2
(-2850 1025);
DISPLAY 1.595745 (-2850 1025);
PAINT GREEN (-2850 1025);
DISPLAY INVISIBLE (-2850 1025);
FORCEPROP 2 LAST CDS_LIB mstr_standard
J 0
(-2850 1075);
PAINT MONO (-2850 1075);
DISPLAY INVISIBLE (-2850 1075);
FORCEADD TAP..6
R 2
(-2850 1225);
FORCEPROP 3 LASTPIN (-2900 1225) SIG_NAME M_F_CS_N<5>
J 0
(-2890 1235);
DISPLAY 0.659574 (-2890 1235);
PAINT MONO (-2890 1235);
DISPLAY INVISIBLE (-2890 1235);
FORCEPROP 1 LASTPIN (-2900 1225) BN 5
J 2
(-2848 1233);
DISPLAY 0.617021 (-2848 1233);
PAINT PINK (-2848 1233);
FORCEPROP 1 LAST PATH I94
J 2
(-2848 1225);
DISPLAY 0.872340 (-2848 1225);
PAINT GREEN (-2848 1225);
DISPLAY INVISIBLE (-2848 1225);
FORCEPROP 1 LAST HDL_TAP TRUE
J 2
(-3175 1100);
DISPLAY 1.595745 (-3175 1100);
PAINT GREEN (-3175 1100);
DISPLAY INVISIBLE (-3175 1100);
FORCEPROP 1 LAST BODY_TYPE PLUMBING
J 2
(-2850 1175);
DISPLAY 1.595745 (-2850 1175);
PAINT GREEN (-2850 1175);
DISPLAY INVISIBLE (-2850 1175);
FORCEPROP 2 LAST CDS_LIB mstr_standard
J 0
(-2850 1225);
PAINT MONO (-2850 1225);
DISPLAY INVISIBLE (-2850 1225);
FORCEADD TAP..6
R 2
(-2850 1125);
FORCEPROP 3 LASTPIN (-2900 1125) SIG_NAME M_F_CS_N<3>
J 0
(-2890 1135);
DISPLAY 0.659574 (-2890 1135);
PAINT MONO (-2890 1135);
DISPLAY INVISIBLE (-2890 1135);
FORCEPROP 1 LASTPIN (-2900 1125) BN 3
J 2
(-2848 1133);
DISPLAY 0.617021 (-2848 1133);
PAINT PINK (-2848 1133);
FORCEPROP 1 LAST PATH I95
J 2
(-2848 1125);
DISPLAY 0.872340 (-2848 1125);
PAINT GREEN (-2848 1125);
DISPLAY INVISIBLE (-2848 1125);
FORCEPROP 1 LAST HDL_TAP TRUE
J 2
(-3175 1000);
DISPLAY 1.595745 (-3175 1000);
PAINT GREEN (-3175 1000);
DISPLAY INVISIBLE (-3175 1000);
FORCEPROP 1 LAST BODY_TYPE PLUMBING
J 2
(-2850 1075);
DISPLAY 1.595745 (-2850 1075);
PAINT GREEN (-2850 1075);
DISPLAY INVISIBLE (-2850 1075);
FORCEPROP 2 LAST CDS_LIB mstr_standard
J 0
(-2850 1125);
PAINT MONO (-2850 1125);
DISPLAY INVISIBLE (-2850 1125);
FORCEADD TAP..6
R 2
(-2850 1175);
FORCEPROP 3 LASTPIN (-2900 1175) SIG_NAME M_F_CS_N<4>
J 0
(-2890 1185);
DISPLAY 0.659574 (-2890 1185);
PAINT MONO (-2890 1185);
DISPLAY INVISIBLE (-2890 1185);
FORCEPROP 1 LASTPIN (-2900 1175) BN 4
J 2
(-2848 1183);
DISPLAY 0.617021 (-2848 1183);
PAINT PINK (-2848 1183);
FORCEPROP 1 LAST PATH I96
J 2
(-2848 1175);
DISPLAY 0.872340 (-2848 1175);
PAINT GREEN (-2848 1175);
DISPLAY INVISIBLE (-2848 1175);
FORCEPROP 1 LAST HDL_TAP TRUE
J 2
(-3175 1050);
DISPLAY 1.595745 (-3175 1050);
PAINT GREEN (-3175 1050);
DISPLAY INVISIBLE (-3175 1050);
FORCEPROP 1 LAST BODY_TYPE PLUMBING
J 2
(-2850 1125);
DISPLAY 1.595745 (-2850 1125);
PAINT GREEN (-2850 1125);
DISPLAY INVISIBLE (-2850 1125);
FORCEPROP 2 LAST CDS_LIB mstr_standard
J 0
(-2850 1175);
PAINT MONO (-2850 1175);
DISPLAY INVISIBLE (-2850 1175);
FORCEADD TAP..6
R 2
(-2850 1275);
FORCEPROP 3 LASTPIN (-2900 1275) SIG_NAME M_F_CS_N<6>
J 0
(-2890 1285);
DISPLAY 0.659574 (-2890 1285);
PAINT MONO (-2890 1285);
DISPLAY INVISIBLE (-2890 1285);
FORCEPROP 1 LASTPIN (-2900 1275) BN 6
J 2
(-2848 1283);
DISPLAY 0.617021 (-2848 1283);
PAINT PINK (-2848 1283);
FORCEPROP 1 LAST PATH I97
J 2
(-2848 1275);
DISPLAY 0.872340 (-2848 1275);
PAINT GREEN (-2848 1275);
DISPLAY INVISIBLE (-2848 1275);
FORCEPROP 1 LAST HDL_TAP TRUE
J 2
(-3175 1150);
DISPLAY 1.595745 (-3175 1150);
PAINT GREEN (-3175 1150);
DISPLAY INVISIBLE (-3175 1150);
FORCEPROP 1 LAST BODY_TYPE PLUMBING
J 2
(-2850 1225);
DISPLAY 1.595745 (-2850 1225);
PAINT GREEN (-2850 1225);
DISPLAY INVISIBLE (-2850 1225);
FORCEPROP 2 LAST CDS_LIB mstr_standard
J 0
(-2850 1275);
PAINT MONO (-2850 1275);
DISPLAY INVISIBLE (-2850 1275);
FORCEADD TAP..6
R 2
(-2850 1325);
FORCEPROP 3 LASTPIN (-2900 1325) SIG_NAME M_F_CS_N<7>
J 0
(-2890 1335);
DISPLAY 0.659574 (-2890 1335);
PAINT MONO (-2890 1335);
DISPLAY INVISIBLE (-2890 1335);
FORCEPROP 1 LASTPIN (-2900 1325) BN 7
J 2
(-2848 1333);
DISPLAY 0.617021 (-2848 1333);
PAINT PINK (-2848 1333);
FORCEPROP 1 LAST PATH I98
J 2
(-2848 1325);
DISPLAY 0.872340 (-2848 1325);
PAINT GREEN (-2848 1325);
DISPLAY INVISIBLE (-2848 1325);
FORCEPROP 1 LAST HDL_TAP TRUE
J 2
(-3175 1200);
DISPLAY 1.595745 (-3175 1200);
PAINT GREEN (-3175 1200);
DISPLAY INVISIBLE (-3175 1200);
FORCEPROP 1 LAST BODY_TYPE PLUMBING
J 2
(-2850 1275);
DISPLAY 1.595745 (-2850 1275);
PAINT GREEN (-2850 1275);
DISPLAY INVISIBLE (-2850 1275);
FORCEPROP 2 LAST CDS_LIB mstr_standard
J 0
(-2850 1325);
PAINT MONO (-2850 1325);
DISPLAY INVISIBLE (-2850 1325);
FORCEADD TAP..6
R 2
(-2850 1475);
FORCEPROP 3 LASTPIN (-2900 1475) SIG_NAME M_F_ODT<1>
J 0
(-2890 1485);
DISPLAY 0.659574 (-2890 1485);
PAINT MONO (-2890 1485);
DISPLAY INVISIBLE (-2890 1485);
FORCEPROP 1 LASTPIN (-2900 1475) BN 1
J 2
(-2848 1483);
DISPLAY 0.617021 (-2848 1483);
PAINT PINK (-2848 1483);
FORCEPROP 1 LAST PATH I99
J 2
(-2848 1475);
DISPLAY 0.872340 (-2848 1475);
PAINT GREEN (-2848 1475);
DISPLAY INVISIBLE (-2848 1475);
FORCEPROP 1 LAST HDL_TAP TRUE
J 2
(-3175 1350);
DISPLAY 1.595745 (-3175 1350);
PAINT GREEN (-3175 1350);
DISPLAY INVISIBLE (-3175 1350);
FORCEPROP 1 LAST BODY_TYPE PLUMBING
J 2
(-2850 1425);
DISPLAY 1.595745 (-2850 1425);
PAINT GREEN (-2850 1425);
DISPLAY INVISIBLE (-2850 1425);
FORCEPROP 2 LAST CDS_LIB mstr_standard
J 0
(-2850 1475);
PAINT MONO (-2850 1475);
DISPLAY INVISIBLE (-2850 1475);
FORCEADD INTEL_CORP_BPAGE..1
(0 0);
FORCEPROP 1 LAST CDS_CON_LAST_MODIFIED Fri Jun 16 17:48:11 2017
J 0
(-1425 325);
DISPLAY 1.340426 (-1425 325);
PAINT GREEN (-1425 325);
DISPLAY INVISIBLE (-1425 325);
FORCEPROP 1 LAST CUSTOM_TXT_CDS <CURRENT_DESIGN_SHEET> OF <TOTAL_DESIGN_SHEETS>
J 0
(-500 25);
PAINT ORANGE (-500 25);
FORCEPROP 1 LAST CUSTOM_TXT_CDS <CON_LAST_MODIFIED>
J 0
(-4000 100);
PAINT ORANGE (-4000 100);
FORCEPROP 2 LAST CUSTOM_TXT_CDS <XR_PAGE_TITLE>
J 0
(-7890 5250);
DISPLAY 0.638298 (-7890 5250);
PAINT PINK (-7890 5250);
DISPLAY INVISIBLE (-7890 5250);
FORCEPROP 1 LAST SCH_TITLE SKYLAKE - SKT0 - 8 OF 21
J 0
(-7950 50);
DISPLAY 1.212766 (-7950 50);
PAINT GREEN (-7950 50);
FORCEPROP 1 LAST COMMENT_BODY TRUE
J 0
(12 12);
DISPLAY 0.638298 (12 12);
PAINT GREEN (12 12);
DISPLAY INVISIBLE (12 12);
FORCEPROP 2 LAST PAGE_BORDER TRUE
J 0
(-7890 5250);
DISPLAY 0.851064 (-7890 5250);
PAINT PINK (-7890 5250);
DISPLAY INVISIBLE (-7890 5250);
FORCEPROP 2 LAST CDS_LIB mstr_symbols
J 0
(0 0);
PAINT ORANGE (0 0);
DISPLAY INVISIBLE (0 0);
FORCEPROP 2 LAST CDS_XR_PAGE_TITLE CR-28 : @BASEBOARD_FAB2_LIB.BASEBOARD_FAB2(SCH_1):PAGE28
J 0
(-7890 5250);
DISPLAY 0.638298 (-7890 5250);
PAINT PINK (-7890 5250);
DISPLAY INVISIBLE (-7890 5250);
FORCEADD DESIGN_NOTE..1
(-6500 400);
FORCEPROP 0 LAST L1 CPU SYMBOLS 1-30 ARE PRELIMINARY AND SUBJECT TO CHANGE
J 0
(-6700 275);
DISPLAY 1.021277 (-6700 275);
PAINT ORANGE (-6700 275);
FORCEPROP 1 LAST COMMENT_BODY TRUE
J 0
(-6475 500);
DISPLAY 0.978723 (-6475 500);
PAINT ORANGE (-6475 500);
DISPLAY INVISIBLE (-6475 500);
FORCEPROP 2 LAST CDS_LIB mstr_symbols
J 0
(-6500 400);
PAINT ORANGE (-6500 400);
DISPLAY INVISIBLE (-6500 400);
FORCEADD PRELIM..10
(-4215 2565);
PAINT GRAY (-4215 2565);
FORCEPROP 1 LAST COMMENT_BODY TRUE
J 0
(-4215 2565);
PAINT ORANGE (-4215 2565);
DISPLAY INVISIBLE (-4215 2565);
FORCEPROP 2 LAST CDS_LIB mstr_misc
J 0
(-4215 2565);
PAINT ORANGE (-4215 2565);
DISPLAY INVISIBLE (-4215 2565);
WIRE 17 -1 (-2050 4750)(-2800 4750);
FORCEPROP 2 LAST SIG_NAME M_F_DQS_DP<17:0>
J 0
(-2700 4760);
DISPLAY 0.617021 (-2700 4760);
PAINT ORANGE (-2700 4760);
WIRE 17 -1 (-2800 4700)(-2800 4750);
WIRE 17 -1 (-2800 4650)(-2800 4700);
WIRE 17 -1 (-2800 4600)(-2800 4650);
WIRE 17 -1 (-2800 4550)(-2800 4600);
WIRE 17 -1 (-2800 3850)(-2800 3900);
WIRE 17 -1 (-2800 3900)(-2800 3950);
WIRE 17 -1 (-2800 4500)(-2800 4550);
WIRE 17 -1 (-2800 4450)(-2800 4500);
WIRE 17 -1 (-2800 3950)(-2800 4000);
WIRE 17 -1 (-2800 4000)(-2800 4050);
WIRE 17 -1 (-2800 4400)(-2800 4450);
WIRE 17 -1 (-2800 4350)(-2800 4400);
WIRE 17 -1 (-2800 4050)(-2800 4100);
WIRE 17 -1 (-2800 4100)(-2800 4150);
WIRE 17 -1 (-2800 4300)(-2800 4350);
WIRE 17 -1 (-2800 4250)(-2800 4300);
WIRE 17 -1 (-2800 4150)(-2800 4200);
WIRE 17 -1 (-2800 4200)(-2800 4250);
WIRE 17 -1 (-5625 1475)(-6375 1475);
FORCEPROP 2 LAST SIG_NAME M_F_ECC<7:0>
J 0
(-6325 1485);
DISPLAY 0.617021 (-6325 1485);
PAINT ORANGE (-6325 1485);
WIRE 17 -1 (-5625 1450)(-5625 1475);
WIRE 17 -1 (-5625 1400)(-5625 1450);
WIRE 17 -1 (-5625 1350)(-5625 1400);
WIRE 17 -1 (-5625 1300)(-5625 1350);
WIRE 17 -1 (-5625 1250)(-5625 1300);
WIRE 17 -1 (-5625 1200)(-5625 1250);
WIRE 17 -1 (-5625 1100)(-5625 1150);
WIRE 17 -1 (-5625 1150)(-5625 1200);
WIRE 17 -1 (-5625 1550)(-5625 1600);
WIRE 17 -1 (-5625 1600)(-5625 1650);
WIRE 17 -1 (-5625 1650)(-5625 1700);
WIRE 17 -1 (-5625 1700)(-5625 1750);
WIRE 17 -1 (-5625 1750)(-5625 1800);
WIRE 17 -1 (-5625 1800)(-5625 1850);
WIRE 17 -1 (-5625 1850)(-5625 1900);
WIRE 17 -1 (-5625 1900)(-5625 1950);
WIRE 17 -1 (-5625 1950)(-5625 2000);
WIRE 17 -1 (-5625 2000)(-5625 2050);
WIRE 17 -1 (-5625 2050)(-5625 2100);
WIRE 17 -1 (-5625 2100)(-5625 2150);
WIRE 17 -1 (-5625 2150)(-5625 2200);
WIRE 17 -1 (-5625 2200)(-5625 2250);
WIRE 17 -1 (-5625 2250)(-5625 2300);
WIRE 17 -1 (-5625 2300)(-5625 2350);
WIRE 17 -1 (-5625 2350)(-5625 2400);
WIRE 17 -1 (-5625 4800)(-6375 4800);
FORCEPROP 2 LAST SIG_NAME M_F_DQ<63:0>
J 0
(-6325 4810);
DISPLAY 0.617021 (-6325 4810);
PAINT ORANGE (-6325 4810);
WIRE 17 -1 (-5625 4700)(-5625 4800);
WIRE 17 -1 (-5625 2400)(-5625 2450);
WIRE 17 -1 (-5625 2450)(-5625 2500);
WIRE 17 -1 (-5625 4650)(-5625 4700);
WIRE 17 -1 (-5625 4600)(-5625 4650);
WIRE 17 -1 (-5625 2500)(-5625 2550);
WIRE 17 -1 (-5625 2550)(-5625 2600);
WIRE 17 -1 (-5625 4550)(-5625 4600);
WIRE 17 -1 (-5625 4500)(-5625 4550);
WIRE 17 -1 (-5625 2600)(-5625 2650);
WIRE 17 -1 (-5625 2650)(-5625 2700);
WIRE 17 -1 (-5625 4450)(-5625 4500);
WIRE 17 -1 (-5625 4400)(-5625 4450);
WIRE 17 -1 (-5625 2700)(-5625 2750);
WIRE 17 -1 (-5625 2750)(-5625 2800);
WIRE 17 -1 (-5625 4350)(-5625 4400);
WIRE 17 -1 (-5625 4300)(-5625 4350);
WIRE 17 -1 (-5625 2800)(-5625 2850);
WIRE 17 -1 (-5625 2850)(-5625 2900);
WIRE 17 -1 (-5625 4250)(-5625 4300);
WIRE 17 -1 (-5625 4200)(-5625 4250);
WIRE 17 -1 (-5625 2900)(-5625 2950);
WIRE 17 -1 (-5625 2950)(-5625 3000);
WIRE 17 -1 (-5625 4150)(-5625 4200);
WIRE 17 -1 (-5625 4100)(-5625 4150);
WIRE 17 -1 (-5625 3000)(-5625 3050);
WIRE 17 -1 (-5625 3050)(-5625 3100);
WIRE 17 -1 (-5625 4050)(-5625 4100);
WIRE 17 -1 (-5625 4000)(-5625 4050);
WIRE 17 -1 (-5625 3100)(-5625 3150);
WIRE 17 -1 (-5625 3150)(-5625 3200);
WIRE 17 -1 (-5625 3950)(-5625 4000);
WIRE 17 -1 (-5625 3900)(-5625 3950);
WIRE 17 -1 (-5625 3200)(-5625 3250);
WIRE 17 -1 (-5625 3250)(-5625 3300);
WIRE 17 -1 (-5625 3850)(-5625 3900);
WIRE 17 -1 (-5625 3800)(-5625 3850);
WIRE 17 -1 (-5625 3300)(-5625 3350);
WIRE 17 -1 (-5625 3350)(-5625 3400);
WIRE 17 -1 (-5625 3750)(-5625 3800);
WIRE 17 -1 (-5625 3700)(-5625 3750);
WIRE 17 -1 (-5625 3400)(-5625 3450);
WIRE 17 -1 (-5625 3450)(-5625 3500);
WIRE 17 -1 (-5625 3650)(-5625 3700);
WIRE 17 -1 (-5625 3600)(-5625 3650);
WIRE 17 -1 (-5625 3500)(-5625 3550);
WIRE 17 -1 (-5625 3550)(-5625 3600);
WIRE 17 -1 (-2050 1625)(-2800 1625);
FORCEPROP 2 LAST SIG_NAME M_F_ODT<3:0>
J 0
(-2700 1635);
DISPLAY 0.617021 (-2700 1635);
PAINT ORANGE (-2700 1635);
WIRE 17 -1 (-2800 1600)(-2800 1625);
WIRE 17 -1 (-2800 1550)(-2800 1600);
WIRE 17 -1 (-2800 1450)(-2800 1500);
WIRE 17 -1 (-2800 1500)(-2800 1550);
WIRE 17 -1 (-5625 1025)(-6375 1025);
FORCEPROP 2 LAST SIG_NAME M_F_CLK_DP<3:0>
J 0
(-6325 1035);
DISPLAY 0.617021 (-6325 1035);
PAINT ORANGE (-6325 1035);
WIRE 17 -1 (-5625 1000)(-5625 1025);
WIRE 17 -1 (-5625 950)(-5625 1000);
WIRE 17 -1 (-5625 900)(-5625 950);
WIRE 17 -1 (-5625 850)(-5625 900);
WIRE 17 -1 (-5625 825)(-6375 825);
FORCEPROP 2 LAST SIG_NAME M_F_CLK_DN<3:0>
J 0
(-6325 835);
DISPLAY 0.617021 (-6325 835);
PAINT ORANGE (-6325 835);
WIRE 17 -1 (-5625 800)(-5625 825);
WIRE 17 -1 (-5625 750)(-5625 800);
WIRE 17 -1 (-5625 700)(-5625 750);
WIRE 17 -1 (-5625 650)(-5625 700);
WIRE 17 -1 (-2050 2825)(-2800 2825);
FORCEPROP 2 LAST SIG_NAME M_F_MA<17:0>
J 0
(-2700 2835);
DISPLAY 0.617021 (-2700 2835);
PAINT ORANGE (-2700 2835);
WIRE 17 -1 (-2800 2800)(-2800 2825);
WIRE 17 -1 (-2800 2750)(-2800 2800);
WIRE 17 -1 (-2800 2700)(-2800 2750);
WIRE 17 -1 (-2800 2650)(-2800 2700);
WIRE 17 -1 (-2800 2600)(-2800 2650);
WIRE 17 -1 (-2800 2550)(-2800 2600);
WIRE 17 -1 (-2800 2500)(-2800 2550);
WIRE 17 -1 (-2800 2450)(-2800 2500);
WIRE 17 -1 (-2800 2400)(-2800 2450);
WIRE 17 -1 (-2800 2350)(-2800 2400);
WIRE 17 -1 (-2800 2300)(-2800 2350);
WIRE 17 -1 (-2800 2250)(-2800 2300);
WIRE 17 -1 (-2800 2200)(-2800 2250);
WIRE 17 -1 (-2800 2150)(-2800 2200);
WIRE 17 -1 (-2800 2100)(-2800 2150);
WIRE 17 -1 (-2800 2050)(-2800 2100);
WIRE 17 -1 (-2800 2000)(-2800 2050);
WIRE 17 -1 (-2800 1950)(-2800 2000);
WIRE 17 -1 (-2050 1375)(-2800 1375);
FORCEPROP 2 LAST SIG_NAME M_F_CS_N<7:0>
J 0
(-2700 1385);
DISPLAY 0.617021 (-2700 1385);
PAINT ORANGE (-2700 1385);
WIRE 17 -1 (-2800 1350)(-2800 1375);
WIRE 17 -1 (-2800 1300)(-2800 1350);
WIRE 17 -1 (-2800 1250)(-2800 1300);
WIRE 17 -1 (-2800 1200)(-2800 1250);
WIRE 17 -1 (-2800 1150)(-2800 1200);
WIRE 17 -1 (-2800 1100)(-2800 1150);
WIRE 17 -1 (-2800 1050)(-2800 1100);
WIRE 17 -1 (-2800 1000)(-2800 1050);
WIRE 17 -1 (-2050 1875)(-2800 1875);
FORCEPROP 2 LAST SIG_NAME M_F_CKE<3:0>
J 0
(-2700 1885);
DISPLAY 0.617021 (-2700 1885);
PAINT ORANGE (-2700 1885);
WIRE 17 -1 (-2800 1850)(-2800 1875);
WIRE 17 -1 (-2800 1800)(-2800 1850);
WIRE 17 -1 (-2800 1750)(-2800 1800);
WIRE 17 -1 (-2800 1700)(-2800 1750);
WIRE 17 -1 (-2050 925)(-2800 925);
FORCEPROP 2 LAST SIG_NAME M_F_BG<1:0>
J 0
(-2700 935);
DISPLAY 0.617021 (-2700 935);
PAINT ORANGE (-2700 935);
WIRE 17 -1 (-2800 900)(-2800 925);
WIRE 17 -1 (-2800 850)(-2800 900);
WIRE 17 -1 (-2050 825)(-2800 825);
FORCEPROP 2 LAST SIG_NAME M_F_BA<1:0>
J 0
(-2700 835);
DISPLAY 0.617021 (-2700 835);
PAINT ORANGE (-2700 835);
WIRE 17 -1 (-2800 800)(-2800 825);
WIRE 17 -1 (-2800 750)(-2800 800);
WIRE 17 -1 (-2050 3775)(-2800 3775);
FORCEPROP 2 LAST SIG_NAME M_F_DQS_DN<17:0>
J 0
(-2700 3785);
DISPLAY 0.617021 (-2700 3785);
PAINT ORANGE (-2700 3785);
WIRE 17 -1 (-2800 3750)(-2800 3775);
WIRE 17 -1 (-2800 3700)(-2800 3750);
WIRE 17 -1 (-2800 3650)(-2800 3700);
WIRE 17 -1 (-2800 3600)(-2800 3650);
WIRE 17 -1 (-2800 3550)(-2800 3600);
WIRE 17 -1 (-2800 3500)(-2800 3550);
WIRE 17 -1 (-2800 3450)(-2800 3500);
WIRE 17 -1 (-2800 3400)(-2800 3450);
WIRE 17 -1 (-2800 3350)(-2800 3400);
WIRE 17 -1 (-2800 3300)(-2800 3350);
WIRE 17 -1 (-2800 3250)(-2800 3300);
WIRE 17 -1 (-2800 3200)(-2800 3250);
WIRE 17 -1 (-2800 3150)(-2800 3200);
WIRE 17 -1 (-2800 3100)(-2800 3150);
WIRE 17 -1 (-2800 3050)(-2800 3100);
WIRE 17 -1 (-2800 3000)(-2800 3050);
WIRE 17 -1 (-2800 2950)(-2800 3000);
WIRE 17 -1 (-2800 2900)(-2800 2950);
WIRE 16 -1 (-3325 3575)(-2900 3575);
WIRE 16 -1 (-5025 4025)(-5525 4025);
WIRE 16 -1 (-5025 4275)(-5525 4275);
WIRE 16 -1 (-5025 4325)(-5525 4325);
WIRE 16 -1 (-5025 4375)(-5525 4375);
WIRE 16 -1 (-3325 4675)(-2900 4675);
WIRE 16 -1 (-3325 4625)(-2900 4625);
WIRE 16 -1 (-3325 4575)(-2900 4575);
WIRE 16 -1 (-3325 4525)(-2900 4525);
WIRE 16 -1 (-3325 4475)(-2900 4475);
WIRE 16 -1 (-3325 4425)(-2900 4425);
WIRE 16 -1 (-3325 4375)(-2900 4375);
WIRE 16 -1 (-3325 4325)(-2900 4325);
WIRE 16 -1 (-3325 4275)(-2900 4275);
WIRE 16 -1 (-3325 4175)(-2900 4175);
WIRE 16 -1 (-3325 4125)(-2900 4125);
WIRE 16 -1 (-3325 3725)(-2900 3725);
WIRE 16 -1 (-3325 3675)(-2900 3675);
WIRE 16 -1 (-3325 3625)(-2900 3625);
WIRE 16 -1 (-3325 3525)(-2900 3525);
WIRE 16 -1 (-3325 3475)(-2900 3475);
WIRE 16 -1 (-3325 3425)(-2900 3425);
WIRE 16 -1 (-3325 3375)(-2900 3375);
WIRE 16 -1 (-2900 3325)(-3325 3325);
WIRE 16 -1 (-2900 3275)(-3325 3275);
WIRE 16 -1 (-2900 3225)(-3325 3225);
WIRE 16 -1 (-2900 3175)(-3325 3175);
WIRE 16 -1 (-3325 3125)(-2900 3125);
WIRE 16 -1 (-2900 3075)(-3325 3075);
WIRE 16 -1 (-2900 3025)(-3325 3025);
WIRE 16 -1 (-2900 2975)(-3325 2975);
WIRE 16 -1 (-2900 2925)(-3325 2925);
WIRE 16 -1 (-3325 2875)(-2900 2875);
WIRE 16 -1 (-3325 4075)(-2900 4075);
WIRE 16 -1 (-3325 4025)(-2900 4025);
WIRE 16 -1 (-3325 3975)(-2900 3975);
WIRE 16 -1 (-3325 3875)(-2900 3875);
WIRE 16 -1 (-3325 3825)(-2900 3825);
WIRE 16 -1 (-2900 2775)(-3325 2775);
WIRE 16 -1 (-3325 2725)(-2900 2725);
WIRE 16 -1 (-2900 2675)(-3325 2675);
WIRE 16 -1 (-2900 2625)(-3325 2625);
WIRE 16 -1 (-2900 2575)(-3325 2575);
WIRE 16 -1 (-2900 2525)(-3325 2525);
WIRE 16 -1 (-3325 2475)(-2900 2475);
WIRE 16 -1 (-2900 2425)(-3325 2425);
WIRE 16 -1 (-2900 2375)(-3325 2375);
WIRE 16 -1 (-3325 2325)(-2900 2325);
WIRE 16 -1 (-2900 2275)(-3325 2275);
WIRE 16 -1 (-3325 2225)(-2900 2225);
WIRE 16 -1 (-3325 2175)(-2900 2175);
WIRE 16 -1 (-2900 2125)(-3325 2125);
WIRE 16 -1 (-3325 2075)(-2900 2075);
WIRE 16 -1 (-3325 625)(-2050 625);
FORCEPROP 2 LAST SIG_NAME M_F_ACT_N
J 0
(-2725 635);
DISPLAY 0.617021 (-2725 635);
PAINT ORANGE (-2725 635);
WIRE 16 -1 (-3325 525)(-2050 525);
FORCEPROP 2 LAST SIG_NAME M_F_PAR
J 0
(-2725 535);
DISPLAY 0.617021 (-2725 535);
PAINT ORANGE (-2725 535);
WIRE 16 -1 (-3325 575)(-2050 575);
FORCEPROP 2 LAST SIG_NAME M_F_ALERT_N
J 0
(-2725 585);
DISPLAY 0.617021 (-2725 585);
PAINT ORANGE (-2725 585);
WIRE 16 -1 (-3325 775)(-2900 775);
WIRE 16 -1 (-3325 725)(-2900 725);
WIRE 16 -1 (-3325 875)(-2900 875);
WIRE 16 -1 (-3325 825)(-2900 825);
WIRE 16 -1 (-3325 1825)(-2900 1825);
WIRE 16 -1 (-3325 1775)(-2900 1775);
WIRE 16 -1 (-3325 1725)(-2900 1725);
WIRE 16 -1 (-3325 1675)(-2900 1675);
WIRE 16 -1 (-3325 1325)(-2900 1325);
WIRE 16 -1 (-3325 1275)(-2900 1275);
WIRE 16 -1 (-3325 1225)(-2900 1225);
WIRE 16 -1 (-3325 1175)(-2900 1175);
WIRE 16 -1 (-3325 1125)(-2900 1125);
WIRE 16 -1 (-3325 1075)(-2900 1075);
WIRE 16 -1 (-3325 1025)(-2900 1025);
WIRE 16 -1 (-3325 975)(-2900 975);
WIRE 16 -1 (-3325 2025)(-2900 2025);
WIRE 16 -1 (-3325 1975)(-2900 1975);
WIRE 16 -1 (-3325 1925)(-2900 1925);
WIRE 16 -1 (-3325 1575)(-2900 1575);
WIRE 16 -1 (-3325 1475)(-2900 1475);
WIRE 16 -1 (-3325 1425)(-2900 1425);
WIRE 16 -1 (-5025 4675)(-5525 4675);
WIRE 16 -1 (-5025 4625)(-5525 4625);
WIRE 16 -1 (-5025 4575)(-5525 4575);
WIRE 16 -1 (-5025 4525)(-5525 4525);
WIRE 16 -1 (-5025 4475)(-5525 4475);
WIRE 16 -1 (-5025 4425)(-5525 4425);
WIRE 16 -1 (-5025 4225)(-5525 4225);
WIRE 16 -1 (-5025 4175)(-5525 4175);
WIRE 16 -1 (-5025 4075)(-5525 4075);
WIRE 16 -1 (-5025 3975)(-5525 3975);
WIRE 16 -1 (-5025 3925)(-5525 3925);
WIRE 16 -1 (-5025 3875)(-5525 3875);
WIRE 16 -1 (-5025 3825)(-5525 3825);
WIRE 16 -1 (-5025 3775)(-5525 3775);
WIRE 16 -1 (-5025 3725)(-5525 3725);
WIRE 16 -1 (-5025 3675)(-5525 3675);
WIRE 16 -1 (-5525 3625)(-5025 3625);
WIRE 16 -1 (-5025 3525)(-5525 3525);
WIRE 16 -1 (-5525 3475)(-5025 3475);
WIRE 16 -1 (-5525 3425)(-5025 3425);
WIRE 16 -1 (-5025 3375)(-5525 3375);
WIRE 16 -1 (-5525 3325)(-5025 3325);
WIRE 16 -1 (-5525 3275)(-5025 3275);
WIRE 16 -1 (-5525 3175)(-5025 3175);
WIRE 16 -1 (-5525 3075)(-5025 3075);
WIRE 16 -1 (-5525 3025)(-5025 3025);
WIRE 16 -1 (-5525 2975)(-5025 2975);
WIRE 16 -1 (-5525 2925)(-5025 2925);
WIRE 16 -1 (-5525 2875)(-5025 2875);
WIRE 16 -1 (-5525 2825)(-5025 2825);
WIRE 16 -1 (-5525 2775)(-5025 2775);
WIRE 16 -1 (-5525 2725)(-5025 2725);
WIRE 16 -1 (-5525 2675)(-5025 2675);
WIRE 16 -1 (-5525 2625)(-5025 2625);
WIRE 16 -1 (-5525 2575)(-5025 2575);
WIRE 16 -1 (-5525 2525)(-5025 2525);
WIRE 16 -1 (-5525 2475)(-5025 2475);
WIRE 16 -1 (-5525 2425)(-5025 2425);
WIRE 16 -1 (-5525 2375)(-5025 2375);
WIRE 16 -1 (-5525 2325)(-5025 2325);
WIRE 16 -1 (-5525 2275)(-5025 2275);
WIRE 16 -1 (-5525 2225)(-5025 2225);
WIRE 16 -1 (-5525 2175)(-5025 2175);
WIRE 16 -1 (-5525 2125)(-5025 2125);
WIRE 16 -1 (-5525 2075)(-5025 2075);
WIRE 16 -1 (-5025 775)(-5525 775);
WIRE 16 -1 (-5025 725)(-5525 725);
WIRE 16 -1 (-5025 675)(-5525 675);
WIRE 16 -1 (-5025 625)(-5525 625);
WIRE 16 -1 (-5025 975)(-5525 975);
WIRE 16 -1 (-5025 925)(-5525 925);
WIRE 16 -1 (-5025 875)(-5525 875);
WIRE 16 -1 (-5025 825)(-5525 825);
WIRE 16 -1 (-5525 2025)(-5025 2025);
WIRE 16 -1 (-5525 1975)(-5025 1975);
WIRE 16 -1 (-5525 1925)(-5025 1925);
WIRE 16 -1 (-5525 1875)(-5025 1875);
WIRE 16 -1 (-5025 1825)(-5525 1825);
WIRE 16 -1 (-5525 1725)(-5025 1725);
WIRE 16 -1 (-5025 1675)(-5525 1675);
WIRE 16 -1 (-5525 1625)(-5025 1625);
WIRE 16 -1 (-5525 1575)(-5025 1575);
WIRE 16 -1 (-5525 1525)(-5025 1525);
WIRE 16 -1 (-5025 1425)(-5525 1425);
WIRE 16 -1 (-5025 1375)(-5525 1375);
WIRE 16 -1 (-5025 1325)(-5525 1325);
WIRE 16 -1 (-5025 1275)(-5525 1275);
WIRE 16 -1 (-5025 1225)(-5525 1225);
WIRE 16 -1 (-5025 1175)(-5525 1175);
WIRE 16 -1 (-5025 1075)(-5525 1075);
WIRE 16 -1 (-5025 525)(-6375 525);
FORCEPROP 2 LAST SIG_NAME M_F_C<2>
J 0
(-6325 535);
DISPLAY 0.617021 (-6325 535);
PAINT ORANGE (-6325 535);
WIRE 16 -1 (-5525 1775)(-5025 1775);
WIRE 16 -1 (-5525 3125)(-5025 3125);
WIRE 16 -1 (-5525 3225)(-5025 3225);
WIRE 16 -1 (-3325 1525)(-2900 1525);
WIRE 16 -1 (-5025 4125)(-5525 4125);
WIRE 16 -1 (-3325 3925)(-2900 3925);
WIRE 16 -1 (-5525 3575)(-5025 3575);
WIRE 16 -1 (-5025 1125)(-5525 1125);
WIRE 16 -1 (-3325 4225)(-2900 4225);
FORCENOTE
BOM_COST=PROC_SOCKET
(-7925 225) 0;
DISPLAY LEFT (-7925 225);
DISPLAY 1.382979 (-7925 225);
PAINT PURPLE (-7925 225);
FORCENOTE
ROOM=CPU0
(-7925 350) 0;
DISPLAY LEFT (-7925 350);
DISPLAY 1.382979 (-7925 350);
PAINT PURPLE (-7925 350);
FORCENOTE
SKYLAKE - SKT0 - 8 OF 21
(-1650 150) 0;
DISPLAY LEFT (-1650 150);
DISPLAY 1.021277 (-1650 150);
PAINT RED (-1650 150);
QUIT
